FILE_TYPE = MACRO_DRAWING;
SET COLOR_WIRE YELLOW;
SET COLOR_PROP MONO;
SET COLOR_DOT WHITE;
SET COLOR_ARC YELLOW;
SET COLOR_BODY GREEN;
SET COLOR_NOTE MONO;
SET PROP_DISPLAY VALUE;
SET PAGE_NUMBER P28;
FORCEADD OFFPAGE..5
(-6425 525);
FORCEPROP 2 LAST $XR0 53 
J 0
(-6679 525);
DISPLAY 0.638298 (-6679 525);
PAINT MONO (-6679 525);
FORCEPROP 2 LAST $XR1 54 
J 0
(-6769 525);
DISPLAY 0.638298 (-6769 525);
PAINT MONO (-6769 525);
FORCEPROP 2 LAST CDS_LIB mstr_standard
J 0
(-6425 525);
PAINT MONO (-6425 525);
DISPLAY INVISIBLE (-6425 525);
FORCEPROP 1 LAST OFFPAGE TRUE
J 0
(-6100 400);
DISPLAY 1.170213 (-6100 400);
PAINT GREEN (-6100 400);
DISPLAY INVISIBLE (-6100 400);
FORCEPROP 1 LAST COMMENT_BODY TRUE
J 0
(-6325 450);
DISPLAY 1.170213 (-6325 450);
PAINT GREEN (-6325 450);
DISPLAY INVISIBLE (-6325 450);
FORCEPROP 2 LAST PATH I1
J 0
(-6375 600);
DISPLAY 1.021277 (-6375 600);
PAINT ORANGE (-6375 600);
DISPLAY INVISIBLE (-6375 600);
FORCEADD TAP..6
(-5575 875);
FORCEPROP 3 LASTPIN (-5525 875) SIG_NAME M_F_CLK_DP<1>
J 0
(-5515 885);
DISPLAY 0.659574 (-5515 885);
PAINT MONO (-5515 885);
DISPLAY INVISIBLE (-5515 885);
FORCEPROP 1 LASTPIN (-5525 875) BN 1
J 0
(-5577 883);
DISPLAY 0.617021 (-5577 883);
PAINT PINK (-5577 883);
FORCEPROP 2 LAST CDS_LIB mstr_standard
J 0
(-5575 875);
PAINT MONO (-5575 875);
DISPLAY INVISIBLE (-5575 875);
FORCEPROP 1 LAST BODY_TYPE PLUMBING
J 0
(-5575 825);
DISPLAY 1.595745 (-5575 825);
PAINT GREEN (-5575 825);
DISPLAY INVISIBLE (-5575 825);
FORCEPROP 1 LAST HDL_TAP TRUE
J 0
(-5250 750);
DISPLAY 1.595745 (-5250 750);
PAINT GREEN (-5250 750);
DISPLAY INVISIBLE (-5250 750);
FORCEPROP 1 LAST PATH I10
J 0
(-5577 875);
DISPLAY 0.872340 (-5577 875);
PAINT GREEN (-5577 875);
DISPLAY INVISIBLE (-5577 875);
FORCEADD TAP..6
R 2
(-2850 1425);
FORCEPROP 3 LASTPIN (-2900 1425) SIG_NAME M_F_ODT<0>
J 0
(-2890 1435);
DISPLAY 0.659574 (-2890 1435);
PAINT MONO (-2890 1435);
DISPLAY INVISIBLE (-2890 1435);
FORCEPROP 1 LASTPIN (-2900 1425) BN 0
J 2
(-2848 1433);
DISPLAY 0.617021 (-2848 1433);
PAINT PINK (-2848 1433);
FORCEPROP 2 LAST CDS_LIB mstr_standard
J 0
(-2850 1425);
PAINT MONO (-2850 1425);
DISPLAY INVISIBLE (-2850 1425);
FORCEPROP 1 LAST BODY_TYPE PLUMBING
J 2
(-2850 1375);
DISPLAY 1.595745 (-2850 1375);
PAINT GREEN (-2850 1375);
DISPLAY INVISIBLE (-2850 1375);
FORCEPROP 1 LAST HDL_TAP TRUE
J 2
(-3175 1300);
DISPLAY 1.595745 (-3175 1300);
PAINT GREEN (-3175 1300);
DISPLAY INVISIBLE (-3175 1300);
FORCEPROP 1 LAST PATH I100
J 2
(-2848 1425);
DISPLAY 0.872340 (-2848 1425);
PAINT GREEN (-2848 1425);
DISPLAY INVISIBLE (-2848 1425);
FORCEADD TAP..6
R 2
(-2850 1575);
FORCEPROP 3 LASTPIN (-2900 1575) SIG_NAME M_F_ODT<3>
J 0
(-2890 1585);
DISPLAY 0.659574 (-2890 1585);
PAINT MONO (-2890 1585);
DISPLAY INVISIBLE (-2890 1585);
FORCEPROP 1 LASTPIN (-2900 1575) BN 3
J 2
(-2848 1583);
DISPLAY 0.617021 (-2848 1583);
PAINT PINK (-2848 1583);
FORCEPROP 2 LAST CDS_LIB mstr_standard
J 0
(-2850 1575);
PAINT MONO (-2850 1575);
DISPLAY INVISIBLE (-2850 1575);
FORCEPROP 1 LAST BODY_TYPE PLUMBING
J 2
(-2850 1525);
DISPLAY 1.595745 (-2850 1525);
PAINT GREEN (-2850 1525);
DISPLAY INVISIBLE (-2850 1525);
FORCEPROP 1 LAST HDL_TAP TRUE
J 2
(-3175 1450);
DISPLAY 1.595745 (-3175 1450);
PAINT GREEN (-3175 1450);
DISPLAY INVISIBLE (-3175 1450);
FORCEPROP 1 LAST PATH I101
J 2
(-2848 1575);
DISPLAY 0.872340 (-2848 1575);
PAINT GREEN (-2848 1575);
DISPLAY INVISIBLE (-2848 1575);
FORCEADD TAP..6
R 2
(-2850 1525);
FORCEPROP 3 LASTPIN (-2900 1525) SIG_NAME M_F_ODT<2>
J 0
(-2890 1535);
DISPLAY 0.659574 (-2890 1535);
PAINT MONO (-2890 1535);
DISPLAY INVISIBLE (-2890 1535);
FORCEPROP 1 LASTPIN (-2900 1525) BN 2
J 2
(-2848 1533);
DISPLAY 0.617021 (-2848 1533);
PAINT PINK (-2848 1533);
FORCEPROP 2 LAST CDS_LIB mstr_standard
J 0
(-2850 1525);
PAINT MONO (-2850 1525);
DISPLAY INVISIBLE (-2850 1525);
FORCEPROP 1 LAST BODY_TYPE PLUMBING
J 2
(-2850 1475);
DISPLAY 1.595745 (-2850 1475);
PAINT GREEN (-2850 1475);
DISPLAY INVISIBLE (-2850 1475);
FORCEPROP 1 LAST HDL_TAP TRUE
J 2
(-3175 1400);
DISPLAY 1.595745 (-3175 1400);
PAINT GREEN (-3175 1400);
DISPLAY INVISIBLE (-3175 1400);
FORCEPROP 1 LAST PATH I102
J 2
(-2848 1525);
DISPLAY 0.872340 (-2848 1525);
PAINT GREEN (-2848 1525);
DISPLAY INVISIBLE (-2848 1525);
FORCEADD TAP..6
R 2
(-2850 1675);
FORCEPROP 3 LASTPIN (-2900 1675) SIG_NAME M_F_CKE<0>
J 0
(-2890 1685);
DISPLAY 0.659574 (-2890 1685);
PAINT MONO (-2890 1685);
DISPLAY INVISIBLE (-2890 1685);
FORCEPROP 1 LASTPIN (-2900 1675) BN 0
J 2
(-2848 1683);
DISPLAY 0.617021 (-2848 1683);
PAINT PINK (-2848 1683);
FORCEPROP 2 LAST CDS_LIB mstr_standard
J 0
(-2850 1675);
PAINT MONO (-2850 1675);
DISPLAY INVISIBLE (-2850 1675);
FORCEPROP 1 LAST BODY_TYPE PLUMBING
J 2
(-2850 1625);
DISPLAY 1.595745 (-2850 1625);
PAINT GREEN (-2850 1625);
DISPLAY INVISIBLE (-2850 1625);
FORCEPROP 1 LAST HDL_TAP TRUE
J 2
(-3175 1550);
DISPLAY 1.595745 (-3175 1550);
PAINT GREEN (-3175 1550);
DISPLAY INVISIBLE (-3175 1550);
FORCEPROP 1 LAST PATH I103
J 2
(-2848 1675);
DISPLAY 0.872340 (-2848 1675);
PAINT GREEN (-2848 1675);
DISPLAY INVISIBLE (-2848 1675);
FORCEADD TAP..6
R 2
(-2850 1725);
FORCEPROP 3 LASTPIN (-2900 1725) SIG_NAME M_F_CKE<1>
J 0
(-2890 1735);
DISPLAY 0.659574 (-2890 1735);
PAINT MONO (-2890 1735);
DISPLAY INVISIBLE (-2890 1735);
FORCEPROP 1 LASTPIN (-2900 1725) BN 1
J 2
(-2848 1733);
DISPLAY 0.617021 (-2848 1733);
PAINT PINK (-2848 1733);
FORCEPROP 2 LAST CDS_LIB mstr_standard
J 0
(-2850 1725);
PAINT MONO (-2850 1725);
DISPLAY INVISIBLE (-2850 1725);
FORCEPROP 1 LAST BODY_TYPE PLUMBING
J 2
(-2850 1675);
DISPLAY 1.595745 (-2850 1675);
PAINT GREEN (-2850 1675);
DISPLAY INVISIBLE (-2850 1675);
FORCEPROP 1 LAST HDL_TAP TRUE
J 2
(-3175 1600);
DISPLAY 1.595745 (-3175 1600);
PAINT GREEN (-3175 1600);
DISPLAY INVISIBLE (-3175 1600);
FORCEPROP 1 LAST PATH I104
J 2
(-2848 1725);
DISPLAY 0.872340 (-2848 1725);
PAINT GREEN (-2848 1725);
DISPLAY INVISIBLE (-2848 1725);
FORCEADD TAP..6
R 2
(-2850 1825);
FORCEPROP 3 LASTPIN (-2900 1825) SIG_NAME M_F_CKE<3>
J 0
(-2890 1835);
DISPLAY 0.659574 (-2890 1835);
PAINT MONO (-2890 1835);
DISPLAY INVISIBLE (-2890 1835);
FORCEPROP 1 LASTPIN (-2900 1825) BN 3
J 2
(-2848 1833);
DISPLAY 0.617021 (-2848 1833);
PAINT PINK (-2848 1833);
FORCEPROP 2 LAST CDS_LIB mstr_standard
J 0
(-2850 1825);
PAINT MONO (-2850 1825);
DISPLAY INVISIBLE (-2850 1825);
FORCEPROP 1 LAST BODY_TYPE PLUMBING
J 2
(-2850 1775);
DISPLAY 1.595745 (-2850 1775);
PAINT GREEN (-2850 1775);
DISPLAY INVISIBLE (-2850 1775);
FORCEPROP 1 LAST HDL_TAP TRUE
J 2
(-3175 1700);
DISPLAY 1.595745 (-3175 1700);
PAINT GREEN (-3175 1700);
DISPLAY INVISIBLE (-3175 1700);
FORCEPROP 1 LAST PATH I105
J 2
(-2848 1825);
DISPLAY 0.872340 (-2848 1825);
PAINT GREEN (-2848 1825);
DISPLAY INVISIBLE (-2848 1825);
FORCEADD TAP..6
R 2
(-2850 1775);
FORCEPROP 3 LASTPIN (-2900 1775) SIG_NAME M_F_CKE<2>
J 0
(-2890 1785);
DISPLAY 0.659574 (-2890 1785);
PAINT MONO (-2890 1785);
DISPLAY INVISIBLE (-2890 1785);
FORCEPROP 1 LASTPIN (-2900 1775) BN 2
J 2
(-2848 1783);
DISPLAY 0.617021 (-2848 1783);
PAINT PINK (-2848 1783);
FORCEPROP 2 LAST CDS_LIB mstr_standard
J 0
(-2850 1775);
PAINT MONO (-2850 1775);
DISPLAY INVISIBLE (-2850 1775);
FORCEPROP 1 LAST BODY_TYPE PLUMBING
J 2
(-2850 1725);
DISPLAY 1.595745 (-2850 1725);
PAINT GREEN (-2850 1725);
DISPLAY INVISIBLE (-2850 1725);
FORCEPROP 1 LAST HDL_TAP TRUE
J 2
(-3175 1650);
DISPLAY 1.595745 (-3175 1650);
PAINT GREEN (-3175 1650);
DISPLAY INVISIBLE (-3175 1650);
FORCEPROP 1 LAST PATH I106
J 2
(-2848 1775);
DISPLAY 0.872340 (-2848 1775);
PAINT GREEN (-2848 1775);
DISPLAY INVISIBLE (-2848 1775);
FORCEADD TAP..6
R 2
(-2850 1925);
FORCEPROP 3 LASTPIN (-2900 1925) SIG_NAME M_F_MA<0>
J 0
(-2890 1935);
DISPLAY 0.659574 (-2890 1935);
PAINT MONO (-2890 1935);
DISPLAY INVISIBLE (-2890 1935);
FORCEPROP 1 LASTPIN (-2900 1925) BN 0
J 2
(-2848 1933);
DISPLAY 0.617021 (-2848 1933);
PAINT PINK (-2848 1933);
FORCEPROP 2 LAST CDS_LIB mstr_standard
J 0
(-2850 1925);
PAINT MONO (-2850 1925);
DISPLAY INVISIBLE (-2850 1925);
FORCEPROP 1 LAST BODY_TYPE PLUMBING
J 2
(-2850 1875);
DISPLAY 1.595745 (-2850 1875);
PAINT GREEN (-2850 1875);
DISPLAY INVISIBLE (-2850 1875);
FORCEPROP 1 LAST HDL_TAP TRUE
J 2
(-3175 1800);
DISPLAY 1.595745 (-3175 1800);
PAINT GREEN (-3175 1800);
DISPLAY INVISIBLE (-3175 1800);
FORCEPROP 1 LAST PATH I107
J 2
(-2848 1925);
DISPLAY 0.872340 (-2848 1925);
PAINT GREEN (-2848 1925);
DISPLAY INVISIBLE (-2848 1925);
FORCEADD TAP..6
R 2
(-2850 1975);
FORCEPROP 3 LASTPIN (-2900 1975) SIG_NAME M_F_MA<1>
J 0
(-2890 1985);
DISPLAY 0.659574 (-2890 1985);
PAINT MONO (-2890 1985);
DISPLAY INVISIBLE (-2890 1985);
FORCEPROP 1 LASTPIN (-2900 1975) BN 1
J 2
(-2848 1983);
DISPLAY 0.617021 (-2848 1983);
PAINT PINK (-2848 1983);
FORCEPROP 2 LAST CDS_LIB mstr_standard
J 0
(-2850 1975);
PAINT MONO (-2850 1975);
DISPLAY INVISIBLE (-2850 1975);
FORCEPROP 1 LAST BODY_TYPE PLUMBING
J 2
(-2850 1925);
DISPLAY 1.595745 (-2850 1925);
PAINT GREEN (-2850 1925);
DISPLAY INVISIBLE (-2850 1925);
FORCEPROP 1 LAST HDL_TAP TRUE
J 2
(-3175 1850);
DISPLAY 1.595745 (-3175 1850);
PAINT GREEN (-3175 1850);
DISPLAY INVISIBLE (-3175 1850);
FORCEPROP 1 LAST PATH I108
J 2
(-2848 1975);
DISPLAY 0.872340 (-2848 1975);
PAINT GREEN (-2848 1975);
DISPLAY INVISIBLE (-2848 1975);
FORCEADD TAP..6
R 2
(-2850 2075);
FORCEPROP 3 LASTPIN (-2900 2075) SIG_NAME M_F_MA<3>
J 0
(-2890 2085);
DISPLAY 0.659574 (-2890 2085);
PAINT MONO (-2890 2085);
DISPLAY INVISIBLE (-2890 2085);
FORCEPROP 1 LASTPIN (-2900 2075) BN 3
J 2
(-2848 2083);
DISPLAY 0.617021 (-2848 2083);
PAINT PINK (-2848 2083);
FORCEPROP 2 LAST CDS_LIB mstr_standard
J 0
(-2850 2075);
PAINT MONO (-2850 2075);
DISPLAY INVISIBLE (-2850 2075);
FORCEPROP 1 LAST BODY_TYPE PLUMBING
J 2
(-2850 2025);
DISPLAY 1.595745 (-2850 2025);
PAINT GREEN (-2850 2025);
DISPLAY INVISIBLE (-2850 2025);
FORCEPROP 1 LAST HDL_TAP TRUE
J 2
(-3175 1950);
DISPLAY 1.595745 (-3175 1950);
PAINT GREEN (-3175 1950);
DISPLAY INVISIBLE (-3175 1950);
FORCEPROP 1 LAST PATH I109
J 2
(-2848 2075);
DISPLAY 0.872340 (-2848 2075);
PAINT GREEN (-2848 2075);
DISPLAY INVISIBLE (-2848 2075);
FORCEADD TAP..6
(-5575 925);
FORCEPROP 3 LASTPIN (-5525 925) SIG_NAME M_F_CLK_DP<2>
J 0
(-5515 935);
DISPLAY 0.659574 (-5515 935);
PAINT MONO (-5515 935);
DISPLAY INVISIBLE (-5515 935);
FORCEPROP 1 LASTPIN (-5525 925) BN 2
J 0
(-5577 933);
DISPLAY 0.617021 (-5577 933);
PAINT PINK (-5577 933);
FORCEPROP 2 LAST CDS_LIB mstr_standard
J 0
(-5575 925);
PAINT MONO (-5575 925);
DISPLAY INVISIBLE (-5575 925);
FORCEPROP 1 LAST BODY_TYPE PLUMBING
J 0
(-5575 875);
DISPLAY 1.595745 (-5575 875);
PAINT GREEN (-5575 875);
DISPLAY INVISIBLE (-5575 875);
FORCEPROP 1 LAST HDL_TAP TRUE
J 0
(-5250 800);
DISPLAY 1.595745 (-5250 800);
PAINT GREEN (-5250 800);
DISPLAY INVISIBLE (-5250 800);
FORCEPROP 1 LAST PATH I11
J 0
(-5577 925);
DISPLAY 0.872340 (-5577 925);
PAINT GREEN (-5577 925);
DISPLAY INVISIBLE (-5577 925);
FORCEADD TAP..6
R 2
(-2850 2025);
FORCEPROP 3 LASTPIN (-2900 2025) SIG_NAME M_F_MA<2>
J 0
(-2890 2035);
DISPLAY 0.659574 (-2890 2035);
PAINT MONO (-2890 2035);
DISPLAY INVISIBLE (-2890 2035);
FORCEPROP 1 LASTPIN (-2900 2025) BN 2
J 2
(-2848 2033);
DISPLAY 0.617021 (-2848 2033);
PAINT PINK (-2848 2033);
FORCEPROP 2 LAST CDS_LIB mstr_standard
J 0
(-2850 2025);
PAINT MONO (-2850 2025);
DISPLAY INVISIBLE (-2850 2025);
FORCEPROP 1 LAST BODY_TYPE PLUMBING
J 2
(-2850 1975);
DISPLAY 1.595745 (-2850 1975);
PAINT GREEN (-2850 1975);
DISPLAY INVISIBLE (-2850 1975);
FORCEPROP 1 LAST HDL_TAP TRUE
J 2
(-3175 1900);
DISPLAY 1.595745 (-3175 1900);
PAINT GREEN (-3175 1900);
DISPLAY INVISIBLE (-3175 1900);
FORCEPROP 1 LAST PATH I110
J 2
(-2848 2025);
DISPLAY 0.872340 (-2848 2025);
PAINT GREEN (-2848 2025);
DISPLAY INVISIBLE (-2848 2025);
FORCEADD TAP..6
R 2
(-2850 2125);
FORCEPROP 3 LASTPIN (-2900 2125) SIG_NAME M_F_MA<4>
J 0
(-2890 2135);
DISPLAY 0.659574 (-2890 2135);
PAINT MONO (-2890 2135);
DISPLAY INVISIBLE (-2890 2135);
FORCEPROP 1 LASTPIN (-2900 2125) BN 4
J 2
(-2848 2133);
DISPLAY 0.617021 (-2848 2133);
PAINT PINK (-2848 2133);
FORCEPROP 2 LAST CDS_LIB mstr_standard
J 0
(-2850 2125);
PAINT MONO (-2850 2125);
DISPLAY INVISIBLE (-2850 2125);
FORCEPROP 1 LAST BODY_TYPE PLUMBING
J 2
(-2850 2075);
DISPLAY 1.595745 (-2850 2075);
PAINT GREEN (-2850 2075);
DISPLAY INVISIBLE (-2850 2075);
FORCEPROP 1 LAST HDL_TAP TRUE
J 2
(-3175 2000);
DISPLAY 1.595745 (-3175 2000);
PAINT GREEN (-3175 2000);
DISPLAY INVISIBLE (-3175 2000);
FORCEPROP 1 LAST PATH I111
J 2
(-2848 2125);
DISPLAY 0.872340 (-2848 2125);
PAINT GREEN (-2848 2125);
DISPLAY INVISIBLE (-2848 2125);
FORCEADD TAP..6
R 2
(-2850 2175);
FORCEPROP 3 LASTPIN (-2900 2175) SIG_NAME M_F_MA<5>
J 0
(-2890 2185);
DISPLAY 0.659574 (-2890 2185);
PAINT MONO (-2890 2185);
DISPLAY INVISIBLE (-2890 2185);
FORCEPROP 1 LASTPIN (-2900 2175) BN 5
J 2
(-2848 2183);
DISPLAY 0.617021 (-2848 2183);
PAINT PINK (-2848 2183);
FORCEPROP 2 LAST CDS_LIB mstr_standard
J 0
(-2850 2175);
PAINT MONO (-2850 2175);
DISPLAY INVISIBLE (-2850 2175);
FORCEPROP 1 LAST BODY_TYPE PLUMBING
J 2
(-2850 2125);
DISPLAY 1.595745 (-2850 2125);
PAINT GREEN (-2850 2125);
DISPLAY INVISIBLE (-2850 2125);
FORCEPROP 1 LAST HDL_TAP TRUE
J 2
(-3175 2050);
DISPLAY 1.595745 (-3175 2050);
PAINT GREEN (-3175 2050);
DISPLAY INVISIBLE (-3175 2050);
FORCEPROP 1 LAST PATH I112
J 2
(-2848 2175);
DISPLAY 0.872340 (-2848 2175);
PAINT GREEN (-2848 2175);
DISPLAY INVISIBLE (-2848 2175);
FORCEADD TAP..6
R 2
(-2850 2225);
FORCEPROP 3 LASTPIN (-2900 2225) SIG_NAME M_F_MA<6>
J 0
(-2890 2235);
DISPLAY 0.659574 (-2890 2235);
PAINT MONO (-2890 2235);
DISPLAY INVISIBLE (-2890 2235);
FORCEPROP 1 LASTPIN (-2900 2225) BN 6
J 2
(-2848 2233);
DISPLAY 0.617021 (-2848 2233);
PAINT PINK (-2848 2233);
FORCEPROP 2 LAST CDS_LIB mstr_standard
J 0
(-2850 2225);
PAINT MONO (-2850 2225);
DISPLAY INVISIBLE (-2850 2225);
FORCEPROP 1 LAST BODY_TYPE PLUMBING
J 2
(-2850 2175);
DISPLAY 1.595745 (-2850 2175);
PAINT GREEN (-2850 2175);
DISPLAY INVISIBLE (-2850 2175);
FORCEPROP 1 LAST HDL_TAP TRUE
J 2
(-3175 2100);
DISPLAY 1.595745 (-3175 2100);
PAINT GREEN (-3175 2100);
DISPLAY INVISIBLE (-3175 2100);
FORCEPROP 1 LAST PATH I113
J 2
(-2848 2225);
DISPLAY 0.872340 (-2848 2225);
PAINT GREEN (-2848 2225);
DISPLAY INVISIBLE (-2848 2225);
FORCEADD TAP..6
R 2
(-2850 2375);
FORCEPROP 3 LASTPIN (-2900 2375) SIG_NAME M_F_MA<9>
J 0
(-2890 2385);
DISPLAY 0.659574 (-2890 2385);
PAINT MONO (-2890 2385);
DISPLAY INVISIBLE (-2890 2385);
FORCEPROP 1 LASTPIN (-2900 2375) BN 9
J 2
(-2848 2383);
DISPLAY 0.617021 (-2848 2383);
PAINT PINK (-2848 2383);
FORCEPROP 2 LAST CDS_LIB mstr_standard
J 0
(-2850 2375);
PAINT MONO (-2850 2375);
DISPLAY INVISIBLE (-2850 2375);
FORCEPROP 1 LAST BODY_TYPE PLUMBING
J 2
(-2850 2325);
DISPLAY 1.595745 (-2850 2325);
PAINT GREEN (-2850 2325);
DISPLAY INVISIBLE (-2850 2325);
FORCEPROP 1 LAST HDL_TAP TRUE
J 2
(-3175 2250);
DISPLAY 1.595745 (-3175 2250);
PAINT GREEN (-3175 2250);
DISPLAY INVISIBLE (-3175 2250);
FORCEPROP 1 LAST PATH I114
J 2
(-2848 2375);
DISPLAY 0.872340 (-2848 2375);
PAINT GREEN (-2848 2375);
DISPLAY INVISIBLE (-2848 2375);
FORCEADD TAP..6
R 2
(-2850 2325);
FORCEPROP 3 LASTPIN (-2900 2325) SIG_NAME M_F_MA<8>
J 0
(-2890 2335);
DISPLAY 0.659574 (-2890 2335);
PAINT MONO (-2890 2335);
DISPLAY INVISIBLE (-2890 2335);
FORCEPROP 1 LASTPIN (-2900 2325) BN 8
J 2
(-2848 2333);
DISPLAY 0.617021 (-2848 2333);
PAINT PINK (-2848 2333);
FORCEPROP 2 LAST CDS_LIB mstr_standard
J 0
(-2850 2325);
PAINT MONO (-2850 2325);
DISPLAY INVISIBLE (-2850 2325);
FORCEPROP 1 LAST BODY_TYPE PLUMBING
J 2
(-2850 2275);
DISPLAY 1.595745 (-2850 2275);
PAINT GREEN (-2850 2275);
DISPLAY INVISIBLE (-2850 2275);
FORCEPROP 1 LAST HDL_TAP TRUE
J 2
(-3175 2200);
DISPLAY 1.595745 (-3175 2200);
PAINT GREEN (-3175 2200);
DISPLAY INVISIBLE (-3175 2200);
FORCEPROP 1 LAST PATH I115
J 2
(-2848 2325);
DISPLAY 0.872340 (-2848 2325);
PAINT GREEN (-2848 2325);
DISPLAY INVISIBLE (-2848 2325);
FORCEADD TAP..6
R 2
(-2850 2275);
FORCEPROP 3 LASTPIN (-2900 2275) SIG_NAME M_F_MA<7>
J 0
(-2890 2285);
DISPLAY 0.659574 (-2890 2285);
PAINT MONO (-2890 2285);
DISPLAY INVISIBLE (-2890 2285);
FORCEPROP 1 LASTPIN (-2900 2275) BN 7
J 2
(-2848 2283);
DISPLAY 0.617021 (-2848 2283);
PAINT PINK (-2848 2283);
FORCEPROP 2 LAST CDS_LIB mstr_standard
J 0
(-2850 2275);
PAINT MONO (-2850 2275);
DISPLAY INVISIBLE (-2850 2275);
FORCEPROP 1 LAST BODY_TYPE PLUMBING
J 2
(-2850 2225);
DISPLAY 1.595745 (-2850 2225);
PAINT GREEN (-2850 2225);
DISPLAY INVISIBLE (-2850 2225);
FORCEPROP 1 LAST HDL_TAP TRUE
J 2
(-3175 2150);
DISPLAY 1.595745 (-3175 2150);
PAINT GREEN (-3175 2150);
DISPLAY INVISIBLE (-3175 2150);
FORCEPROP 1 LAST PATH I116
J 2
(-2848 2275);
DISPLAY 0.872340 (-2848 2275);
PAINT GREEN (-2848 2275);
DISPLAY INVISIBLE (-2848 2275);
FORCEADD TAP..6
R 2
(-2850 2475);
FORCEPROP 3 LASTPIN (-2900 2475) SIG_NAME M_F_MA<11>
J 0
(-2890 2485);
DISPLAY 0.659574 (-2890 2485);
PAINT MONO (-2890 2485);
DISPLAY INVISIBLE (-2890 2485);
FORCEPROP 1 LASTPIN (-2900 2475) BN 11
J 2
(-2848 2483);
DISPLAY 0.617021 (-2848 2483);
PAINT PINK (-2848 2483);
FORCEPROP 2 LAST CDS_LIB mstr_standard
J 0
(-2850 2475);
PAINT MONO (-2850 2475);
DISPLAY INVISIBLE (-2850 2475);
FORCEPROP 1 LAST BODY_TYPE PLUMBING
J 2
(-2850 2425);
DISPLAY 1.595745 (-2850 2425);
PAINT GREEN (-2850 2425);
DISPLAY INVISIBLE (-2850 2425);
FORCEPROP 1 LAST HDL_TAP TRUE
J 2
(-3175 2350);
DISPLAY 1.595745 (-3175 2350);
PAINT GREEN (-3175 2350);
DISPLAY INVISIBLE (-3175 2350);
FORCEPROP 1 LAST PATH I117
J 2
(-2848 2475);
DISPLAY 0.872340 (-2848 2475);
PAINT GREEN (-2848 2475);
DISPLAY INVISIBLE (-2848 2475);
FORCEADD TAP..6
R 2
(-2850 2425);
FORCEPROP 3 LASTPIN (-2900 2425) SIG_NAME M_F_MA<10>
J 0
(-2890 2435);
DISPLAY 0.659574 (-2890 2435);
PAINT MONO (-2890 2435);
DISPLAY INVISIBLE (-2890 2435);
FORCEPROP 1 LASTPIN (-2900 2425) BN 10
J 2
(-2848 2433);
DISPLAY 0.617021 (-2848 2433);
PAINT PINK (-2848 2433);
FORCEPROP 2 LAST CDS_LIB mstr_standard
J 0
(-2850 2425);
PAINT MONO (-2850 2425);
DISPLAY INVISIBLE (-2850 2425);
FORCEPROP 1 LAST BODY_TYPE PLUMBING
J 2
(-2850 2375);
DISPLAY 1.595745 (-2850 2375);
PAINT GREEN (-2850 2375);
DISPLAY INVISIBLE (-2850 2375);
FORCEPROP 1 LAST HDL_TAP TRUE
J 2
(-3175 2300);
DISPLAY 1.595745 (-3175 2300);
PAINT GREEN (-3175 2300);
DISPLAY INVISIBLE (-3175 2300);
FORCEPROP 1 LAST PATH I118
J 2
(-2848 2425);
DISPLAY 0.872340 (-2848 2425);
PAINT GREEN (-2848 2425);
DISPLAY INVISIBLE (-2848 2425);
FORCEADD TAP..6
R 2
(-2850 2525);
FORCEPROP 3 LASTPIN (-2900 2525) SIG_NAME M_F_MA<12>
J 0
(-2890 2535);
DISPLAY 0.659574 (-2890 2535);
PAINT MONO (-2890 2535);
DISPLAY INVISIBLE (-2890 2535);
FORCEPROP 1 LASTPIN (-2900 2525) BN 12
J 2
(-2848 2533);
DISPLAY 0.617021 (-2848 2533);
PAINT PINK (-2848 2533);
FORCEPROP 2 LAST CDS_LIB mstr_standard
J 0
(-2850 2525);
PAINT MONO (-2850 2525);
DISPLAY INVISIBLE (-2850 2525);
FORCEPROP 1 LAST BODY_TYPE PLUMBING
J 2
(-2850 2475);
DISPLAY 1.595745 (-2850 2475);
PAINT GREEN (-2850 2475);
DISPLAY INVISIBLE (-2850 2475);
FORCEPROP 1 LAST HDL_TAP TRUE
J 2
(-3175 2400);
DISPLAY 1.595745 (-3175 2400);
PAINT GREEN (-3175 2400);
DISPLAY INVISIBLE (-3175 2400);
FORCEPROP 1 LAST PATH I119
J 2
(-2848 2525);
DISPLAY 0.872340 (-2848 2525);
PAINT GREEN (-2848 2525);
DISPLAY INVISIBLE (-2848 2525);
FORCEADD TAP..6
(-5575 975);
FORCEPROP 3 LASTPIN (-5525 975) SIG_NAME M_F_CLK_DP<3>
J 0
(-5515 985);
DISPLAY 0.659574 (-5515 985);
PAINT MONO (-5515 985);
DISPLAY INVISIBLE (-5515 985);
FORCEPROP 1 LASTPIN (-5525 975) BN 3
J 0
(-5577 983);
DISPLAY 0.617021 (-5577 983);
PAINT PINK (-5577 983);
FORCEPROP 2 LAST CDS_LIB mstr_standard
J 0
(-5575 975);
PAINT MONO (-5575 975);
DISPLAY INVISIBLE (-5575 975);
FORCEPROP 1 LAST BODY_TYPE PLUMBING
J 0
(-5575 925);
DISPLAY 1.595745 (-5575 925);
PAINT GREEN (-5575 925);
DISPLAY INVISIBLE (-5575 925);
FORCEPROP 1 LAST HDL_TAP TRUE
J 0
(-5250 850);
DISPLAY 1.595745 (-5250 850);
PAINT GREEN (-5250 850);
DISPLAY INVISIBLE (-5250 850);
FORCEPROP 1 LAST PATH I12
J 0
(-5577 975);
DISPLAY 0.872340 (-5577 975);
PAINT GREEN (-5577 975);
DISPLAY INVISIBLE (-5577 975);
FORCEADD TAP..6
R 2
(-2850 2575);
FORCEPROP 3 LASTPIN (-2900 2575) SIG_NAME M_F_MA<13>
J 0
(-2890 2585);
DISPLAY 0.659574 (-2890 2585);
PAINT MONO (-2890 2585);
DISPLAY INVISIBLE (-2890 2585);
FORCEPROP 1 LASTPIN (-2900 2575) BN 13
J 2
(-2848 2583);
DISPLAY 0.617021 (-2848 2583);
PAINT PINK (-2848 2583);
FORCEPROP 2 LAST CDS_LIB mstr_standard
J 0
(-2850 2575);
PAINT MONO (-2850 2575);
DISPLAY INVISIBLE (-2850 2575);
FORCEPROP 1 LAST BODY_TYPE PLUMBING
J 2
(-2850 2525);
DISPLAY 1.595745 (-2850 2525);
PAINT GREEN (-2850 2525);
DISPLAY INVISIBLE (-2850 2525);
FORCEPROP 1 LAST HDL_TAP TRUE
J 2
(-3175 2450);
DISPLAY 1.595745 (-3175 2450);
PAINT GREEN (-3175 2450);
DISPLAY INVISIBLE (-3175 2450);
FORCEPROP 1 LAST PATH I120
J 2
(-2848 2575);
DISPLAY 0.872340 (-2848 2575);
PAINT GREEN (-2848 2575);
DISPLAY INVISIBLE (-2848 2575);
FORCEADD TAP..6
R 2
(-2850 2625);
FORCEPROP 3 LASTPIN (-2900 2625) SIG_NAME M_F_MA<14>
J 0
(-2890 2635);
DISPLAY 0.659574 (-2890 2635);
PAINT MONO (-2890 2635);
DISPLAY INVISIBLE (-2890 2635);
FORCEPROP 1 LASTPIN (-2900 2625) BN 14
J 2
(-2848 2633);
DISPLAY 0.617021 (-2848 2633);
PAINT PINK (-2848 2633);
FORCEPROP 2 LAST CDS_LIB mstr_standard
J 0
(-2850 2625);
PAINT MONO (-2850 2625);
DISPLAY INVISIBLE (-2850 2625);
FORCEPROP 1 LAST BODY_TYPE PLUMBING
J 2
(-2850 2575);
DISPLAY 1.595745 (-2850 2575);
PAINT GREEN (-2850 2575);
DISPLAY INVISIBLE (-2850 2575);
FORCEPROP 1 LAST HDL_TAP TRUE
J 2
(-3175 2500);
DISPLAY 1.595745 (-3175 2500);
PAINT GREEN (-3175 2500);
DISPLAY INVISIBLE (-3175 2500);
FORCEPROP 1 LAST PATH I121
J 2
(-2848 2625);
DISPLAY 0.872340 (-2848 2625);
PAINT GREEN (-2848 2625);
DISPLAY INVISIBLE (-2848 2625);
FORCEADD TAP..6
R 2
(-2850 2725);
FORCEPROP 3 LASTPIN (-2900 2725) SIG_NAME M_F_MA<16>
J 0
(-2890 2735);
DISPLAY 0.659574 (-2890 2735);
PAINT MONO (-2890 2735);
DISPLAY INVISIBLE (-2890 2735);
FORCEPROP 1 LASTPIN (-2900 2725) BN 16
J 2
(-2848 2733);
DISPLAY 0.617021 (-2848 2733);
PAINT PINK (-2848 2733);
FORCEPROP 2 LAST CDS_LIB mstr_standard
J 0
(-2850 2725);
PAINT MONO (-2850 2725);
DISPLAY INVISIBLE (-2850 2725);
FORCEPROP 1 LAST BODY_TYPE PLUMBING
J 2
(-2850 2675);
DISPLAY 1.595745 (-2850 2675);
PAINT GREEN (-2850 2675);
DISPLAY INVISIBLE (-2850 2675);
FORCEPROP 1 LAST HDL_TAP TRUE
J 2
(-3175 2600);
DISPLAY 1.595745 (-3175 2600);
PAINT GREEN (-3175 2600);
DISPLAY INVISIBLE (-3175 2600);
FORCEPROP 1 LAST PATH I122
J 2
(-2848 2725);
DISPLAY 0.872340 (-2848 2725);
PAINT GREEN (-2848 2725);
DISPLAY INVISIBLE (-2848 2725);
FORCEADD TAP..6
R 2
(-2850 2675);
FORCEPROP 3 LASTPIN (-2900 2675) SIG_NAME M_F_MA<15>
J 0
(-2890 2685);
DISPLAY 0.659574 (-2890 2685);
PAINT MONO (-2890 2685);
DISPLAY INVISIBLE (-2890 2685);
FORCEPROP 1 LASTPIN (-2900 2675) BN 15
J 2
(-2848 2683);
DISPLAY 0.617021 (-2848 2683);
PAINT PINK (-2848 2683);
FORCEPROP 2 LAST CDS_LIB mstr_standard
J 0
(-2850 2675);
PAINT MONO (-2850 2675);
DISPLAY INVISIBLE (-2850 2675);
FORCEPROP 1 LAST BODY_TYPE PLUMBING
J 2
(-2850 2625);
DISPLAY 1.595745 (-2850 2625);
PAINT GREEN (-2850 2625);
DISPLAY INVISIBLE (-2850 2625);
FORCEPROP 1 LAST HDL_TAP TRUE
J 2
(-3175 2550);
DISPLAY 1.595745 (-3175 2550);
PAINT GREEN (-3175 2550);
DISPLAY INVISIBLE (-3175 2550);
FORCEPROP 1 LAST PATH I123
J 2
(-2848 2675);
DISPLAY 0.872340 (-2848 2675);
PAINT GREEN (-2848 2675);
DISPLAY INVISIBLE (-2848 2675);
FORCEADD TAP..6
R 2
(-2850 2775);
FORCEPROP 3 LASTPIN (-2900 2775) SIG_NAME M_F_MA<17>
J 0
(-2890 2785);
DISPLAY 0.659574 (-2890 2785);
PAINT MONO (-2890 2785);
DISPLAY INVISIBLE (-2890 2785);
FORCEPROP 1 LASTPIN (-2900 2775) BN 17
J 2
(-2848 2783);
DISPLAY 0.617021 (-2848 2783);
PAINT PINK (-2848 2783);
FORCEPROP 2 LAST CDS_LIB mstr_standard
J 0
(-2850 2775);
PAINT MONO (-2850 2775);
DISPLAY INVISIBLE (-2850 2775);
FORCEPROP 1 LAST BODY_TYPE PLUMBING
J 2
(-2850 2725);
DISPLAY 1.595745 (-2850 2725);
PAINT GREEN (-2850 2725);
DISPLAY INVISIBLE (-2850 2725);
FORCEPROP 1 LAST HDL_TAP TRUE
J 2
(-3175 2650);
DISPLAY 1.595745 (-3175 2650);
PAINT GREEN (-3175 2650);
DISPLAY INVISIBLE (-3175 2650);
FORCEPROP 1 LAST PATH I124
J 2
(-2848 2775);
DISPLAY 0.872340 (-2848 2775);
PAINT GREEN (-2848 2775);
DISPLAY INVISIBLE (-2848 2775);
FORCEADD TAP..6
R 2
(-2850 2875);
FORCEPROP 3 LASTPIN (-2900 2875) SIG_NAME M_F_DQS_DN<0>
J 0
(-2890 2885);
DISPLAY 0.659574 (-2890 2885);
PAINT MONO (-2890 2885);
DISPLAY INVISIBLE (-2890 2885);
FORCEPROP 1 LASTPIN (-2900 2875) BN 0
J 2
(-2848 2883);
DISPLAY 0.617021 (-2848 2883);
PAINT PINK (-2848 2883);
FORCEPROP 2 LAST CDS_LIB mstr_standard
J 0
(-2850 2875);
PAINT MONO (-2850 2875);
DISPLAY INVISIBLE (-2850 2875);
FORCEPROP 1 LAST BODY_TYPE PLUMBING
J 2
(-2850 2825);
DISPLAY 1.595745 (-2850 2825);
PAINT GREEN (-2850 2825);
DISPLAY INVISIBLE (-2850 2825);
FORCEPROP 1 LAST HDL_TAP TRUE
J 2
(-3175 2750);
DISPLAY 1.595745 (-3175 2750);
PAINT GREEN (-3175 2750);
DISPLAY INVISIBLE (-3175 2750);
FORCEPROP 1 LAST PATH I125
J 2
(-2848 2875);
DISPLAY 0.872340 (-2848 2875);
PAINT GREEN (-2848 2875);
DISPLAY INVISIBLE (-2848 2875);
FORCEADD TAP..6
R 2
(-2850 2975);
FORCEPROP 3 LASTPIN (-2900 2975) SIG_NAME M_F_DQS_DN<2>
J 0
(-2890 2985);
DISPLAY 0.659574 (-2890 2985);
PAINT MONO (-2890 2985);
DISPLAY INVISIBLE (-2890 2985);
FORCEPROP 1 LASTPIN (-2900 2975) BN 2
J 2
(-2848 2983);
DISPLAY 0.617021 (-2848 2983);
PAINT PINK (-2848 2983);
FORCEPROP 2 LAST CDS_LIB mstr_standard
J 0
(-2850 2975);
PAINT MONO (-2850 2975);
DISPLAY INVISIBLE (-2850 2975);
FORCEPROP 1 LAST BODY_TYPE PLUMBING
J 2
(-2850 2925);
DISPLAY 1.595745 (-2850 2925);
PAINT GREEN (-2850 2925);
DISPLAY INVISIBLE (-2850 2925);
FORCEPROP 1 LAST HDL_TAP TRUE
J 2
(-3175 2850);
DISPLAY 1.595745 (-3175 2850);
PAINT GREEN (-3175 2850);
DISPLAY INVISIBLE (-3175 2850);
FORCEPROP 1 LAST PATH I126
J 2
(-2848 2975);
DISPLAY 0.872340 (-2848 2975);
PAINT GREEN (-2848 2975);
DISPLAY INVISIBLE (-2848 2975);
FORCEADD TAP..6
R 2
(-2850 2925);
FORCEPROP 3 LASTPIN (-2900 2925) SIG_NAME M_F_DQS_DN<1>
J 0
(-2890 2935);
DISPLAY 0.659574 (-2890 2935);
PAINT MONO (-2890 2935);
DISPLAY INVISIBLE (-2890 2935);
FORCEPROP 1 LASTPIN (-2900 2925) BN 1
J 2
(-2848 2933);
DISPLAY 0.617021 (-2848 2933);
PAINT PINK (-2848 2933);
FORCEPROP 2 LAST CDS_LIB mstr_standard
J 0
(-2850 2925);
PAINT MONO (-2850 2925);
DISPLAY INVISIBLE (-2850 2925);
FORCEPROP 1 LAST BODY_TYPE PLUMBING
J 2
(-2850 2875);
DISPLAY 1.595745 (-2850 2875);
PAINT GREEN (-2850 2875);
DISPLAY INVISIBLE (-2850 2875);
FORCEPROP 1 LAST HDL_TAP TRUE
J 2
(-3175 2800);
DISPLAY 1.595745 (-3175 2800);
PAINT GREEN (-3175 2800);
DISPLAY INVISIBLE (-3175 2800);
FORCEPROP 1 LAST PATH I127
J 2
(-2848 2925);
DISPLAY 0.872340 (-2848 2925);
PAINT GREEN (-2848 2925);
DISPLAY INVISIBLE (-2848 2925);
FORCEADD TAP..6
R 2
(-2850 3025);
FORCEPROP 3 LASTPIN (-2900 3025) SIG_NAME M_F_DQS_DN<3>
J 0
(-2890 3035);
DISPLAY 0.659574 (-2890 3035);
PAINT MONO (-2890 3035);
DISPLAY INVISIBLE (-2890 3035);
FORCEPROP 1 LASTPIN (-2900 3025) BN 3
J 2
(-2848 3033);
DISPLAY 0.617021 (-2848 3033);
PAINT PINK (-2848 3033);
FORCEPROP 2 LAST CDS_LIB mstr_standard
J 0
(-2850 3025);
PAINT MONO (-2850 3025);
DISPLAY INVISIBLE (-2850 3025);
FORCEPROP 1 LAST BODY_TYPE PLUMBING
J 2
(-2850 2975);
DISPLAY 1.595745 (-2850 2975);
PAINT GREEN (-2850 2975);
DISPLAY INVISIBLE (-2850 2975);
FORCEPROP 1 LAST HDL_TAP TRUE
J 2
(-3175 2900);
DISPLAY 1.595745 (-3175 2900);
PAINT GREEN (-3175 2900);
DISPLAY INVISIBLE (-3175 2900);
FORCEPROP 1 LAST PATH I128
J 2
(-2848 3025);
DISPLAY 0.872340 (-2848 3025);
PAINT GREEN (-2848 3025);
DISPLAY INVISIBLE (-2848 3025);
FORCEADD TAP..6
R 2
(-2850 3075);
FORCEPROP 3 LASTPIN (-2900 3075) SIG_NAME M_F_DQS_DN<4>
J 0
(-2890 3085);
DISPLAY 0.659574 (-2890 3085);
PAINT MONO (-2890 3085);
DISPLAY INVISIBLE (-2890 3085);
FORCEPROP 1 LASTPIN (-2900 3075) BN 4
J 2
(-2848 3083);
DISPLAY 0.617021 (-2848 3083);
PAINT PINK (-2848 3083);
FORCEPROP 2 LAST CDS_LIB mstr_standard
J 0
(-2850 3075);
PAINT MONO (-2850 3075);
DISPLAY INVISIBLE (-2850 3075);
FORCEPROP 1 LAST BODY_TYPE PLUMBING
J 2
(-2850 3025);
DISPLAY 1.595745 (-2850 3025);
PAINT GREEN (-2850 3025);
DISPLAY INVISIBLE (-2850 3025);
FORCEPROP 1 LAST HDL_TAP TRUE
J 2
(-3175 2950);
DISPLAY 1.595745 (-3175 2950);
PAINT GREEN (-3175 2950);
DISPLAY INVISIBLE (-3175 2950);
FORCEPROP 1 LAST PATH I129
J 2
(-2848 3075);
DISPLAY 0.872340 (-2848 3075);
PAINT GREEN (-2848 3075);
DISPLAY INVISIBLE (-2848 3075);
FORCEADD TAP..6
(-5575 1075);
FORCEPROP 3 LASTPIN (-5525 1075) SIG_NAME M_F_ECC<0>
J 0
(-5515 1085);
DISPLAY 0.659574 (-5515 1085);
PAINT MONO (-5515 1085);
DISPLAY INVISIBLE (-5515 1085);
FORCEPROP 1 LASTPIN (-5525 1075) BN 0
J 0
(-5577 1083);
DISPLAY 0.617021 (-5577 1083);
PAINT PINK (-5577 1083);
FORCEPROP 2 LAST CDS_LIB mstr_standard
J 0
(-5575 1075);
PAINT MONO (-5575 1075);
DISPLAY INVISIBLE (-5575 1075);
FORCEPROP 1 LAST BODY_TYPE PLUMBING
J 0
(-5575 1025);
DISPLAY 1.595745 (-5575 1025);
PAINT GREEN (-5575 1025);
DISPLAY INVISIBLE (-5575 1025);
FORCEPROP 1 LAST HDL_TAP TRUE
J 0
(-5250 950);
DISPLAY 1.595745 (-5250 950);
PAINT GREEN (-5250 950);
DISPLAY INVISIBLE (-5250 950);
FORCEPROP 1 LAST PATH I13
J 0
(-5577 1075);
DISPLAY 0.872340 (-5577 1075);
PAINT GREEN (-5577 1075);
DISPLAY INVISIBLE (-5577 1075);
FORCEADD TAP..6
R 2
(-2850 3125);
FORCEPROP 3 LASTPIN (-2900 3125) SIG_NAME M_F_DQS_DN<5>
J 0
(-2890 3135);
DISPLAY 0.659574 (-2890 3135);
PAINT MONO (-2890 3135);
DISPLAY INVISIBLE (-2890 3135);
FORCEPROP 1 LASTPIN (-2900 3125) BN 5
J 2
(-2848 3133);
DISPLAY 0.617021 (-2848 3133);
PAINT PINK (-2848 3133);
FORCEPROP 2 LAST CDS_LIB mstr_standard
J 0
(-2850 3125);
PAINT MONO (-2850 3125);
DISPLAY INVISIBLE (-2850 3125);
FORCEPROP 1 LAST BODY_TYPE PLUMBING
J 2
(-2850 3075);
DISPLAY 1.595745 (-2850 3075);
PAINT GREEN (-2850 3075);
DISPLAY INVISIBLE (-2850 3075);
FORCEPROP 1 LAST HDL_TAP TRUE
J 2
(-3175 3000);
DISPLAY 1.595745 (-3175 3000);
PAINT GREEN (-3175 3000);
DISPLAY INVISIBLE (-3175 3000);
FORCEPROP 1 LAST PATH I130
J 2
(-2848 3125);
DISPLAY 0.872340 (-2848 3125);
PAINT GREEN (-2848 3125);
DISPLAY INVISIBLE (-2848 3125);
FORCEADD TAP..6
R 2
(-2850 3225);
FORCEPROP 3 LASTPIN (-2900 3225) SIG_NAME M_F_DQS_DN<7>
J 0
(-2890 3235);
DISPLAY 0.659574 (-2890 3235);
PAINT MONO (-2890 3235);
DISPLAY INVISIBLE (-2890 3235);
FORCEPROP 1 LASTPIN (-2900 3225) BN 7
J 2
(-2848 3233);
DISPLAY 0.617021 (-2848 3233);
PAINT PINK (-2848 3233);
FORCEPROP 2 LAST CDS_LIB mstr_standard
J 0
(-2850 3225);
PAINT MONO (-2850 3225);
DISPLAY INVISIBLE (-2850 3225);
FORCEPROP 1 LAST BODY_TYPE PLUMBING
J 2
(-2850 3175);
DISPLAY 1.595745 (-2850 3175);
PAINT GREEN (-2850 3175);
DISPLAY INVISIBLE (-2850 3175);
FORCEPROP 1 LAST HDL_TAP TRUE
J 2
(-3175 3100);
DISPLAY 1.595745 (-3175 3100);
PAINT GREEN (-3175 3100);
DISPLAY INVISIBLE (-3175 3100);
FORCEPROP 1 LAST PATH I131
J 2
(-2848 3225);
DISPLAY 0.872340 (-2848 3225);
PAINT GREEN (-2848 3225);
DISPLAY INVISIBLE (-2848 3225);
FORCEADD TAP..6
R 2
(-2850 3175);
FORCEPROP 3 LASTPIN (-2900 3175) SIG_NAME M_F_DQS_DN<6>
J 0
(-2890 3185);
DISPLAY 0.659574 (-2890 3185);
PAINT MONO (-2890 3185);
DISPLAY INVISIBLE (-2890 3185);
FORCEPROP 1 LASTPIN (-2900 3175) BN 6
J 2
(-2848 3183);
DISPLAY 0.617021 (-2848 3183);
PAINT PINK (-2848 3183);
FORCEPROP 2 LAST CDS_LIB mstr_standard
J 0
(-2850 3175);
PAINT MONO (-2850 3175);
DISPLAY INVISIBLE (-2850 3175);
FORCEPROP 1 LAST BODY_TYPE PLUMBING
J 2
(-2850 3125);
DISPLAY 1.595745 (-2850 3125);
PAINT GREEN (-2850 3125);
DISPLAY INVISIBLE (-2850 3125);
FORCEPROP 1 LAST HDL_TAP TRUE
J 2
(-3175 3050);
DISPLAY 1.595745 (-3175 3050);
PAINT GREEN (-3175 3050);
DISPLAY INVISIBLE (-3175 3050);
FORCEPROP 1 LAST PATH I132
J 2
(-2848 3175);
DISPLAY 0.872340 (-2848 3175);
PAINT GREEN (-2848 3175);
DISPLAY INVISIBLE (-2848 3175);
FORCEADD TAP..6
R 2
(-2850 3275);
FORCEPROP 3 LASTPIN (-2900 3275) SIG_NAME M_F_DQS_DN<8>
J 0
(-2890 3285);
DISPLAY 0.659574 (-2890 3285);
PAINT MONO (-2890 3285);
DISPLAY INVISIBLE (-2890 3285);
FORCEPROP 1 LASTPIN (-2900 3275) BN 8
J 2
(-2848 3283);
DISPLAY 0.617021 (-2848 3283);
PAINT PINK (-2848 3283);
FORCEPROP 2 LAST CDS_LIB mstr_standard
J 0
(-2850 3275);
PAINT MONO (-2850 3275);
DISPLAY INVISIBLE (-2850 3275);
FORCEPROP 1 LAST BODY_TYPE PLUMBING
J 2
(-2850 3225);
DISPLAY 1.595745 (-2850 3225);
PAINT GREEN (-2850 3225);
DISPLAY INVISIBLE (-2850 3225);
FORCEPROP 1 LAST HDL_TAP TRUE
J 2
(-3175 3150);
DISPLAY 1.595745 (-3175 3150);
PAINT GREEN (-3175 3150);
DISPLAY INVISIBLE (-3175 3150);
FORCEPROP 1 LAST PATH I133
J 2
(-2848 3275);
DISPLAY 0.872340 (-2848 3275);
PAINT GREEN (-2848 3275);
DISPLAY INVISIBLE (-2848 3275);
FORCEADD TAP..6
R 2
(-2850 3375);
FORCEPROP 3 LASTPIN (-2900 3375) SIG_NAME M_F_DQS_DN<10>
J 0
(-2890 3385);
DISPLAY 0.659574 (-2890 3385);
PAINT MONO (-2890 3385);
DISPLAY INVISIBLE (-2890 3385);
FORCEPROP 1 LASTPIN (-2900 3375) BN 10
J 2
(-2848 3383);
DISPLAY 0.617021 (-2848 3383);
PAINT PINK (-2848 3383);
FORCEPROP 2 LAST CDS_LIB mstr_standard
J 0
(-2850 3375);
PAINT MONO (-2850 3375);
DISPLAY INVISIBLE (-2850 3375);
FORCEPROP 1 LAST BODY_TYPE PLUMBING
J 2
(-2850 3325);
DISPLAY 1.595745 (-2850 3325);
PAINT GREEN (-2850 3325);
DISPLAY INVISIBLE (-2850 3325);
FORCEPROP 1 LAST HDL_TAP TRUE
J 2
(-3175 3250);
DISPLAY 1.595745 (-3175 3250);
PAINT GREEN (-3175 3250);
DISPLAY INVISIBLE (-3175 3250);
FORCEPROP 1 LAST PATH I134
J 2
(-2848 3375);
DISPLAY 0.872340 (-2848 3375);
PAINT GREEN (-2848 3375);
DISPLAY INVISIBLE (-2848 3375);
FORCEADD TAP..6
R 2
(-2850 3325);
FORCEPROP 3 LASTPIN (-2900 3325) SIG_NAME M_F_DQS_DN<9>
J 0
(-2890 3335);
DISPLAY 0.659574 (-2890 3335);
PAINT MONO (-2890 3335);
DISPLAY INVISIBLE (-2890 3335);
FORCEPROP 1 LASTPIN (-2900 3325) BN 9
J 2
(-2848 3333);
DISPLAY 0.617021 (-2848 3333);
PAINT PINK (-2848 3333);
FORCEPROP 2 LAST CDS_LIB mstr_standard
J 0
(-2850 3325);
PAINT MONO (-2850 3325);
DISPLAY INVISIBLE (-2850 3325);
FORCEPROP 1 LAST BODY_TYPE PLUMBING
J 2
(-2850 3275);
DISPLAY 1.595745 (-2850 3275);
PAINT GREEN (-2850 3275);
DISPLAY INVISIBLE (-2850 3275);
FORCEPROP 1 LAST HDL_TAP TRUE
J 2
(-3175 3200);
DISPLAY 1.595745 (-3175 3200);
PAINT GREEN (-3175 3200);
DISPLAY INVISIBLE (-3175 3200);
FORCEPROP 1 LAST PATH I135
J 2
(-2848 3325);
DISPLAY 0.872340 (-2848 3325);
PAINT GREEN (-2848 3325);
DISPLAY INVISIBLE (-2848 3325);
FORCEADD TAP..6
R 2
(-2850 3525);
FORCEPROP 3 LASTPIN (-2900 3525) SIG_NAME M_F_DQS_DN<13>
J 0
(-2890 3535);
DISPLAY 0.659574 (-2890 3535);
PAINT MONO (-2890 3535);
DISPLAY INVISIBLE (-2890 3535);
FORCEPROP 1 LASTPIN (-2900 3525) BN 13
J 2
(-2848 3533);
DISPLAY 0.617021 (-2848 3533);
PAINT PINK (-2848 3533);
FORCEPROP 2 LAST CDS_LIB mstr_standard
J 0
(-2850 3525);
PAINT MONO (-2850 3525);
DISPLAY INVISIBLE (-2850 3525);
FORCEPROP 1 LAST BODY_TYPE PLUMBING
J 2
(-2850 3475);
DISPLAY 1.595745 (-2850 3475);
PAINT GREEN (-2850 3475);
DISPLAY INVISIBLE (-2850 3475);
FORCEPROP 1 LAST HDL_TAP TRUE
J 2
(-3175 3400);
DISPLAY 1.595745 (-3175 3400);
PAINT GREEN (-3175 3400);
DISPLAY INVISIBLE (-3175 3400);
FORCEPROP 1 LAST PATH I136
J 2
(-2848 3525);
DISPLAY 0.872340 (-2848 3525);
PAINT GREEN (-2848 3525);
DISPLAY INVISIBLE (-2848 3525);
FORCEADD TAP..6
R 2
(-2850 3425);
FORCEPROP 3 LASTPIN (-2900 3425) SIG_NAME M_F_DQS_DN<11>
J 0
(-2890 3435);
DISPLAY 0.659574 (-2890 3435);
PAINT MONO (-2890 3435);
DISPLAY INVISIBLE (-2890 3435);
FORCEPROP 1 LASTPIN (-2900 3425) BN 11
J 2
(-2848 3433);
DISPLAY 0.617021 (-2848 3433);
PAINT PINK (-2848 3433);
FORCEPROP 2 LAST CDS_LIB mstr_standard
J 0
(-2850 3425);
PAINT MONO (-2850 3425);
DISPLAY INVISIBLE (-2850 3425);
FORCEPROP 1 LAST BODY_TYPE PLUMBING
J 2
(-2850 3375);
DISPLAY 1.595745 (-2850 3375);
PAINT GREEN (-2850 3375);
DISPLAY INVISIBLE (-2850 3375);
FORCEPROP 1 LAST HDL_TAP TRUE
J 2
(-3175 3300);
DISPLAY 1.595745 (-3175 3300);
PAINT GREEN (-3175 3300);
DISPLAY INVISIBLE (-3175 3300);
FORCEPROP 1 LAST PATH I137
J 2
(-2848 3425);
DISPLAY 0.872340 (-2848 3425);
PAINT GREEN (-2848 3425);
DISPLAY INVISIBLE (-2848 3425);
FORCEADD TAP..6
R 2
(-2850 3475);
FORCEPROP 3 LASTPIN (-2900 3475) SIG_NAME M_F_DQS_DN<12>
J 0
(-2890 3485);
DISPLAY 0.659574 (-2890 3485);
PAINT MONO (-2890 3485);
DISPLAY INVISIBLE (-2890 3485);
FORCEPROP 1 LASTPIN (-2900 3475) BN 12
J 2
(-2848 3483);
DISPLAY 0.617021 (-2848 3483);
PAINT PINK (-2848 3483);
FORCEPROP 2 LAST CDS_LIB mstr_standard
J 0
(-2850 3475);
PAINT MONO (-2850 3475);
DISPLAY INVISIBLE (-2850 3475);
FORCEPROP 1 LAST BODY_TYPE PLUMBING
J 2
(-2850 3425);
DISPLAY 1.595745 (-2850 3425);
PAINT GREEN (-2850 3425);
DISPLAY INVISIBLE (-2850 3425);
FORCEPROP 1 LAST HDL_TAP TRUE
J 2
(-3175 3350);
DISPLAY 1.595745 (-3175 3350);
PAINT GREEN (-3175 3350);
DISPLAY INVISIBLE (-3175 3350);
FORCEPROP 1 LAST PATH I138
J 2
(-2848 3475);
DISPLAY 0.872340 (-2848 3475);
PAINT GREEN (-2848 3475);
DISPLAY INVISIBLE (-2848 3475);
FORCEADD TAP..6
R 2
(-2850 3625);
FORCEPROP 3 LASTPIN (-2900 3625) SIG_NAME M_F_DQS_DN<15>
J 0
(-2890 3635);
DISPLAY 0.659574 (-2890 3635);
PAINT MONO (-2890 3635);
DISPLAY INVISIBLE (-2890 3635);
FORCEPROP 1 LASTPIN (-2900 3625) BN 15
J 2
(-2848 3633);
DISPLAY 0.617021 (-2848 3633);
PAINT PINK (-2848 3633);
FORCEPROP 2 LAST CDS_LIB mstr_standard
J 0
(-2850 3625);
PAINT MONO (-2850 3625);
DISPLAY INVISIBLE (-2850 3625);
FORCEPROP 1 LAST BODY_TYPE PLUMBING
J 2
(-2850 3575);
DISPLAY 1.595745 (-2850 3575);
PAINT GREEN (-2850 3575);
DISPLAY INVISIBLE (-2850 3575);
FORCEPROP 1 LAST HDL_TAP TRUE
J 2
(-3175 3500);
DISPLAY 1.595745 (-3175 3500);
PAINT GREEN (-3175 3500);
DISPLAY INVISIBLE (-3175 3500);
FORCEPROP 1 LAST PATH I139
J 2
(-2848 3625);
DISPLAY 0.872340 (-2848 3625);
PAINT GREEN (-2848 3625);
DISPLAY INVISIBLE (-2848 3625);
FORCEADD TAP..6
(-5575 1125);
FORCEPROP 3 LASTPIN (-5525 1125) SIG_NAME M_F_ECC<1>
J 0
(-5515 1135);
DISPLAY 0.659574 (-5515 1135);
PAINT MONO (-5515 1135);
DISPLAY INVISIBLE (-5515 1135);
FORCEPROP 1 LASTPIN (-5525 1125) BN 1
J 0
(-5577 1133);
DISPLAY 0.617021 (-5577 1133);
PAINT PINK (-5577 1133);
FORCEPROP 2 LAST CDS_LIB mstr_standard
J 0
(-5575 1125);
PAINT MONO (-5575 1125);
DISPLAY INVISIBLE (-5575 1125);
FORCEPROP 1 LAST BODY_TYPE PLUMBING
J 0
(-5575 1075);
DISPLAY 1.595745 (-5575 1075);
PAINT GREEN (-5575 1075);
DISPLAY INVISIBLE (-5575 1075);
FORCEPROP 1 LAST HDL_TAP TRUE
J 0
(-5250 1000);
DISPLAY 1.595745 (-5250 1000);
PAINT GREEN (-5250 1000);
DISPLAY INVISIBLE (-5250 1000);
FORCEPROP 1 LAST PATH I14
J 0
(-5577 1125);
DISPLAY 0.872340 (-5577 1125);
PAINT GREEN (-5577 1125);
DISPLAY INVISIBLE (-5577 1125);
FORCEADD TAP..6
R 2
(-2850 3575);
FORCEPROP 3 LASTPIN (-2900 3575) SIG_NAME M_F_DQS_DN<14>
J 0
(-2890 3585);
DISPLAY 0.659574 (-2890 3585);
PAINT MONO (-2890 3585);
DISPLAY INVISIBLE (-2890 3585);
FORCEPROP 1 LASTPIN (-2900 3575) BN 14
J 2
(-2848 3583);
DISPLAY 0.617021 (-2848 3583);
PAINT PINK (-2848 3583);
FORCEPROP 2 LAST CDS_LIB mstr_standard
J 0
(-2850 3575);
PAINT MONO (-2850 3575);
DISPLAY INVISIBLE (-2850 3575);
FORCEPROP 1 LAST BODY_TYPE PLUMBING
J 2
(-2850 3525);
DISPLAY 1.595745 (-2850 3525);
PAINT GREEN (-2850 3525);
DISPLAY INVISIBLE (-2850 3525);
FORCEPROP 1 LAST HDL_TAP TRUE
J 2
(-3175 3450);
DISPLAY 1.595745 (-3175 3450);
PAINT GREEN (-3175 3450);
DISPLAY INVISIBLE (-3175 3450);
FORCEPROP 1 LAST PATH I140
J 2
(-2848 3575);
DISPLAY 0.872340 (-2848 3575);
PAINT GREEN (-2848 3575);
DISPLAY INVISIBLE (-2848 3575);
FORCEADD TAP..6
R 2
(-2850 3725);
FORCEPROP 3 LASTPIN (-2900 3725) SIG_NAME M_F_DQS_DN<17>
J 0
(-2890 3735);
DISPLAY 0.659574 (-2890 3735);
PAINT MONO (-2890 3735);
DISPLAY INVISIBLE (-2890 3735);
FORCEPROP 1 LASTPIN (-2900 3725) BN 17
J 2
(-2848 3733);
DISPLAY 0.617021 (-2848 3733);
PAINT PINK (-2848 3733);
FORCEPROP 2 LAST CDS_LIB mstr_standard
J 0
(-2850 3725);
PAINT MONO (-2850 3725);
DISPLAY INVISIBLE (-2850 3725);
FORCEPROP 1 LAST BODY_TYPE PLUMBING
J 2
(-2850 3675);
DISPLAY 1.595745 (-2850 3675);
PAINT GREEN (-2850 3675);
DISPLAY INVISIBLE (-2850 3675);
FORCEPROP 1 LAST HDL_TAP TRUE
J 2
(-3175 3600);
DISPLAY 1.595745 (-3175 3600);
PAINT GREEN (-3175 3600);
DISPLAY INVISIBLE (-3175 3600);
FORCEPROP 1 LAST PATH I141
J 2
(-2848 3725);
DISPLAY 0.872340 (-2848 3725);
PAINT GREEN (-2848 3725);
DISPLAY INVISIBLE (-2848 3725);
FORCEADD TAP..6
R 2
(-2850 3675);
FORCEPROP 3 LASTPIN (-2900 3675) SIG_NAME M_F_DQS_DN<16>
J 0
(-2890 3685);
DISPLAY 0.659574 (-2890 3685);
PAINT MONO (-2890 3685);
DISPLAY INVISIBLE (-2890 3685);
FORCEPROP 1 LASTPIN (-2900 3675) BN 16
J 2
(-2848 3683);
DISPLAY 0.617021 (-2848 3683);
PAINT PINK (-2848 3683);
FORCEPROP 2 LAST CDS_LIB mstr_standard
J 0
(-2850 3675);
PAINT MONO (-2850 3675);
DISPLAY INVISIBLE (-2850 3675);
FORCEPROP 1 LAST BODY_TYPE PLUMBING
J 2
(-2850 3625);
DISPLAY 1.595745 (-2850 3625);
PAINT GREEN (-2850 3625);
DISPLAY INVISIBLE (-2850 3625);
FORCEPROP 1 LAST HDL_TAP TRUE
J 2
(-3175 3550);
DISPLAY 1.595745 (-3175 3550);
PAINT GREEN (-3175 3550);
DISPLAY INVISIBLE (-3175 3550);
FORCEPROP 1 LAST PATH I142
J 2
(-2848 3675);
DISPLAY 0.872340 (-2848 3675);
PAINT GREEN (-2848 3675);
DISPLAY INVISIBLE (-2848 3675);
FORCEADD TAP..6
R 2
(-2850 3875);
FORCEPROP 3 LASTPIN (-2900 3875) SIG_NAME M_F_DQS_DP<1>
J 0
(-2890 3885);
DISPLAY 0.659574 (-2890 3885);
PAINT MONO (-2890 3885);
DISPLAY INVISIBLE (-2890 3885);
FORCEPROP 1 LASTPIN (-2900 3875) BN 1
J 2
(-2848 3883);
DISPLAY 0.617021 (-2848 3883);
PAINT PINK (-2848 3883);
FORCEPROP 2 LAST CDS_LIB mstr_standard
J 0
(-2850 3875);
PAINT MONO (-2850 3875);
DISPLAY INVISIBLE (-2850 3875);
FORCEPROP 1 LAST BODY_TYPE PLUMBING
J 2
(-2850 3825);
DISPLAY 1.595745 (-2850 3825);
PAINT GREEN (-2850 3825);
DISPLAY INVISIBLE (-2850 3825);
FORCEPROP 1 LAST HDL_TAP TRUE
J 2
(-3175 3750);
DISPLAY 1.595745 (-3175 3750);
PAINT GREEN (-3175 3750);
DISPLAY INVISIBLE (-3175 3750);
FORCEPROP 1 LAST PATH I143
J 2
(-2848 3875);
DISPLAY 0.872340 (-2848 3875);
PAINT GREEN (-2848 3875);
DISPLAY INVISIBLE (-2848 3875);
FORCEADD TAP..6
R 2
(-2850 3825);
FORCEPROP 3 LASTPIN (-2900 3825) SIG_NAME M_F_DQS_DP<0>
J 0
(-2890 3835);
DISPLAY 0.659574 (-2890 3835);
PAINT MONO (-2890 3835);
DISPLAY INVISIBLE (-2890 3835);
FORCEPROP 1 LASTPIN (-2900 3825) BN 0
J 2
(-2848 3833);
DISPLAY 0.617021 (-2848 3833);
PAINT PINK (-2848 3833);
FORCEPROP 2 LAST CDS_LIB mstr_standard
J 0
(-2850 3825);
PAINT MONO (-2850 3825);
DISPLAY INVISIBLE (-2850 3825);
FORCEPROP 1 LAST BODY_TYPE PLUMBING
J 2
(-2850 3775);
DISPLAY 1.595745 (-2850 3775);
PAINT GREEN (-2850 3775);
DISPLAY INVISIBLE (-2850 3775);
FORCEPROP 1 LAST HDL_TAP TRUE
J 2
(-3175 3700);
DISPLAY 1.595745 (-3175 3700);
PAINT GREEN (-3175 3700);
DISPLAY INVISIBLE (-3175 3700);
FORCEPROP 1 LAST PATH I144
J 2
(-2848 3825);
DISPLAY 0.872340 (-2848 3825);
PAINT GREEN (-2848 3825);
DISPLAY INVISIBLE (-2848 3825);
FORCEADD TAP..6
R 2
(-2850 4025);
FORCEPROP 3 LASTPIN (-2900 4025) SIG_NAME M_F_DQS_DP<4>
J 0
(-2890 4035);
DISPLAY 0.659574 (-2890 4035);
PAINT MONO (-2890 4035);
DISPLAY INVISIBLE (-2890 4035);
FORCEPROP 1 LASTPIN (-2900 4025) BN 4
J 2
(-2848 4033);
DISPLAY 0.617021 (-2848 4033);
PAINT PINK (-2848 4033);
FORCEPROP 2 LAST CDS_LIB mstr_standard
J 0
(-2850 4025);
PAINT MONO (-2850 4025);
DISPLAY INVISIBLE (-2850 4025);
FORCEPROP 1 LAST BODY_TYPE PLUMBING
J 2
(-2850 3975);
DISPLAY 1.595745 (-2850 3975);
PAINT GREEN (-2850 3975);
DISPLAY INVISIBLE (-2850 3975);
FORCEPROP 1 LAST HDL_TAP TRUE
J 2
(-3175 3900);
DISPLAY 1.595745 (-3175 3900);
PAINT GREEN (-3175 3900);
DISPLAY INVISIBLE (-3175 3900);
FORCEPROP 1 LAST PATH I145
J 2
(-2848 4025);
DISPLAY 0.872340 (-2848 4025);
PAINT GREEN (-2848 4025);
DISPLAY INVISIBLE (-2848 4025);
FORCEADD TAP..6
R 2
(-2850 3975);
FORCEPROP 3 LASTPIN (-2900 3975) SIG_NAME M_F_DQS_DP<3>
J 0
(-2890 3985);
DISPLAY 0.659574 (-2890 3985);
PAINT MONO (-2890 3985);
DISPLAY INVISIBLE (-2890 3985);
FORCEPROP 1 LASTPIN (-2900 3975) BN 3
J 2
(-2848 3983);
DISPLAY 0.617021 (-2848 3983);
PAINT PINK (-2848 3983);
FORCEPROP 2 LAST CDS_LIB mstr_standard
J 0
(-2850 3975);
PAINT MONO (-2850 3975);
DISPLAY INVISIBLE (-2850 3975);
FORCEPROP 1 LAST BODY_TYPE PLUMBING
J 2
(-2850 3925);
DISPLAY 1.595745 (-2850 3925);
PAINT GREEN (-2850 3925);
DISPLAY INVISIBLE (-2850 3925);
FORCEPROP 1 LAST HDL_TAP TRUE
J 2
(-3175 3850);
DISPLAY 1.595745 (-3175 3850);
PAINT GREEN (-3175 3850);
DISPLAY INVISIBLE (-3175 3850);
FORCEPROP 1 LAST PATH I146
J 2
(-2848 3975);
DISPLAY 0.872340 (-2848 3975);
PAINT GREEN (-2848 3975);
DISPLAY INVISIBLE (-2848 3975);
FORCEADD TAP..6
R 2
(-2850 3925);
FORCEPROP 3 LASTPIN (-2900 3925) SIG_NAME M_F_DQS_DP<2>
J 0
(-2890 3935);
DISPLAY 0.659574 (-2890 3935);
PAINT MONO (-2890 3935);
DISPLAY INVISIBLE (-2890 3935);
FORCEPROP 1 LASTPIN (-2900 3925) BN 2
J 2
(-2848 3933);
DISPLAY 0.617021 (-2848 3933);
PAINT PINK (-2848 3933);
FORCEPROP 2 LAST CDS_LIB mstr_standard
J 0
(-2850 3925);
PAINT MONO (-2850 3925);
DISPLAY INVISIBLE (-2850 3925);
FORCEPROP 1 LAST BODY_TYPE PLUMBING
J 2
(-2850 3875);
DISPLAY 1.595745 (-2850 3875);
PAINT GREEN (-2850 3875);
DISPLAY INVISIBLE (-2850 3875);
FORCEPROP 1 LAST HDL_TAP TRUE
J 2
(-3175 3800);
DISPLAY 1.595745 (-3175 3800);
PAINT GREEN (-3175 3800);
DISPLAY INVISIBLE (-3175 3800);
FORCEPROP 1 LAST PATH I147
J 2
(-2848 3925);
DISPLAY 0.872340 (-2848 3925);
PAINT GREEN (-2848 3925);
DISPLAY INVISIBLE (-2848 3925);
FORCEADD OFFPAGE..4
(-2000 575);
FORCEPROP 2 LAST $XR0 53 
J 0
(-1814 575);
DISPLAY 0.638298 (-1814 575);
PAINT MONO (-1814 575);
FORCEPROP 2 LAST $XR1 54 
J 0
(-1724 575);
DISPLAY 0.638298 (-1724 575);
PAINT MONO (-1724 575);
FORCEPROP 2 LAST CDS_LIB mstr_standard
J 0
(-2000 575);
PAINT MONO (-2000 575);
DISPLAY INVISIBLE (-2000 575);
FORCEPROP 1 LAST OFFPAGE TRUE
J 0
(-1675 450);
DISPLAY 1.170213 (-1675 450);
PAINT GREEN (-1675 450);
DISPLAY INVISIBLE (-1675 450);
FORCEPROP 1 LAST COMMENT_BODY TRUE
J 0
(-2025 475);
DISPLAY 1.170213 (-2025 475);
PAINT GREEN (-2025 475);
DISPLAY INVISIBLE (-2025 475);
FORCEPROP 2 LAST PATH I148
J 0
(-1825 650);
DISPLAY 1.021277 (-1825 650);
PAINT ORANGE (-1825 650);
DISPLAY INVISIBLE (-1825 650);
FORCEADD OFFPAGE..2
(-2000 525);
FORCEPROP 2 LAST $XR0 53 
J 0
(-1811 525);
DISPLAY 0.638298 (-1811 525);
PAINT MONO (-1811 525);
FORCEPROP 2 LAST $XR1 54 
J 0
(-1721 525);
DISPLAY 0.638298 (-1721 525);
PAINT MONO (-1721 525);
FORCEPROP 2 LAST CDS_LIB mstr_standard
J 0
(-2000 525);
PAINT MONO (-2000 525);
DISPLAY INVISIBLE (-2000 525);
FORCEPROP 1 LAST OFFPAGE TRUE
J 0
(-1675 400);
DISPLAY 1.170213 (-1675 400);
PAINT GREEN (-1675 400);
DISPLAY INVISIBLE (-1675 400);
FORCEPROP 1 LAST COMMENT_BODY TRUE
J 0
(-2045 430);
DISPLAY 1.170213 (-2045 430);
PAINT GREEN (-2045 430);
DISPLAY INVISIBLE (-2045 430);
FORCEPROP 2 LAST PATH I149
J 0
(-1825 600);
DISPLAY 1.021277 (-1825 600);
PAINT ORANGE (-1825 600);
DISPLAY INVISIBLE (-1825 600);
FORCEADD TAP..6
(-5575 1175);
FORCEPROP 3 LASTPIN (-5525 1175) SIG_NAME M_F_ECC<2>
J 0
(-5515 1185);
DISPLAY 0.659574 (-5515 1185);
PAINT MONO (-5515 1185);
DISPLAY INVISIBLE (-5515 1185);
FORCEPROP 1 LASTPIN (-5525 1175) BN 2
J 0
(-5577 1183);
DISPLAY 0.617021 (-5577 1183);
PAINT PINK (-5577 1183);
FORCEPROP 2 LAST CDS_LIB mstr_standard
J 0
(-5575 1175);
PAINT MONO (-5575 1175);
DISPLAY INVISIBLE (-5575 1175);
FORCEPROP 1 LAST BODY_TYPE PLUMBING
J 0
(-5575 1125);
DISPLAY 1.595745 (-5575 1125);
PAINT GREEN (-5575 1125);
DISPLAY INVISIBLE (-5575 1125);
FORCEPROP 1 LAST HDL_TAP TRUE
J 0
(-5250 1050);
DISPLAY 1.595745 (-5250 1050);
PAINT GREEN (-5250 1050);
DISPLAY INVISIBLE (-5250 1050);
FORCEPROP 1 LAST PATH I15
J 0
(-5577 1175);
DISPLAY 0.872340 (-5577 1175);
PAINT GREEN (-5577 1175);
DISPLAY INVISIBLE (-5577 1175);
FORCEADD OFFPAGE..2
(-2000 625);
FORCEPROP 2 LAST $XR0 53 
J 0
(-1811 625);
DISPLAY 0.638298 (-1811 625);
PAINT MONO (-1811 625);
FORCEPROP 2 LAST $XR1 54 
J 0
(-1721 625);
DISPLAY 0.638298 (-1721 625);
PAINT MONO (-1721 625);
FORCEPROP 2 LAST CDS_LIB mstr_standard
J 0
(-2000 625);
PAINT MONO (-2000 625);
DISPLAY INVISIBLE (-2000 625);
FORCEPROP 1 LAST OFFPAGE TRUE
J 0
(-1675 500);
DISPLAY 1.170213 (-1675 500);
PAINT GREEN (-1675 500);
DISPLAY INVISIBLE (-1675 500);
FORCEPROP 1 LAST COMMENT_BODY TRUE
J 0
(-2045 530);
DISPLAY 1.170213 (-2045 530);
PAINT GREEN (-2045 530);
DISPLAY INVISIBLE (-2045 530);
FORCEPROP 2 LAST PATH I150
J 0
(-1825 700);
DISPLAY 1.021277 (-1825 700);
PAINT ORANGE (-1825 700);
DISPLAY INVISIBLE (-1825 700);
FORCEADD OFFPAGE..2
(-2000 825);
FORCEPROP 2 LAST $XR0 53 
J 0
(-1811 825);
DISPLAY 0.638298 (-1811 825);
PAINT MONO (-1811 825);
FORCEPROP 2 LAST $XR1 54 
J 0
(-1721 825);
DISPLAY 0.638298 (-1721 825);
PAINT MONO (-1721 825);
FORCEPROP 2 LAST CDS_LIB mstr_standard
J 0
(-2000 825);
PAINT MONO (-2000 825);
DISPLAY INVISIBLE (-2000 825);
FORCEPROP 1 LAST OFFPAGE TRUE
J 0
(-1675 700);
DISPLAY 1.170213 (-1675 700);
PAINT GREEN (-1675 700);
DISPLAY INVISIBLE (-1675 700);
FORCEPROP 1 LAST COMMENT_BODY TRUE
J 0
(-2045 730);
DISPLAY 1.170213 (-2045 730);
PAINT GREEN (-2045 730);
DISPLAY INVISIBLE (-2045 730);
FORCEPROP 2 LAST PATH I151
J 0
(-1825 900);
DISPLAY 1.021277 (-1825 900);
PAINT ORANGE (-1825 900);
DISPLAY INVISIBLE (-1825 900);
FORCEADD OFFPAGE..2
(-2000 925);
FORCEPROP 2 LAST $XR0 53 
J 0
(-1811 925);
DISPLAY 0.638298 (-1811 925);
PAINT MONO (-1811 925);
FORCEPROP 2 LAST $XR1 54 
J 0
(-1721 925);
DISPLAY 0.638298 (-1721 925);
PAINT MONO (-1721 925);
FORCEPROP 2 LAST CDS_LIB mstr_standard
J 0
(-2000 925);
PAINT MONO (-2000 925);
DISPLAY INVISIBLE (-2000 925);
FORCEPROP 1 LAST OFFPAGE TRUE
J 0
(-1675 800);
DISPLAY 1.170213 (-1675 800);
PAINT GREEN (-1675 800);
DISPLAY INVISIBLE (-1675 800);
FORCEPROP 1 LAST COMMENT_BODY TRUE
J 0
(-2045 830);
DISPLAY 1.170213 (-2045 830);
PAINT GREEN (-2045 830);
DISPLAY INVISIBLE (-2045 830);
FORCEPROP 2 LAST PATH I152
J 0
(-1825 1000);
DISPLAY 1.021277 (-1825 1000);
PAINT ORANGE (-1825 1000);
DISPLAY INVISIBLE (-1825 1000);
FORCEADD OFFPAGE..2
(-2000 1375);
FORCEPROP 2 LAST $XR0 53 
J 0
(-1811 1375);
DISPLAY 0.638298 (-1811 1375);
PAINT MONO (-1811 1375);
FORCEPROP 2 LAST $XR1 54 
J 0
(-1721 1375);
DISPLAY 0.638298 (-1721 1375);
PAINT MONO (-1721 1375);
FORCEPROP 2 LAST CDS_LIB mstr_standard
J 0
(-2000 1375);
PAINT MONO (-2000 1375);
DISPLAY INVISIBLE (-2000 1375);
FORCEPROP 1 LAST OFFPAGE TRUE
J 0
(-1675 1250);
DISPLAY 1.170213 (-1675 1250);
PAINT GREEN (-1675 1250);
DISPLAY INVISIBLE (-1675 1250);
FORCEPROP 1 LAST COMMENT_BODY TRUE
J 0
(-2045 1280);
DISPLAY 1.170213 (-2045 1280);
PAINT GREEN (-2045 1280);
DISPLAY INVISIBLE (-2045 1280);
FORCEPROP 2 LAST PATH I153
J 0
(-1825 1450);
DISPLAY 1.021277 (-1825 1450);
PAINT ORANGE (-1825 1450);
DISPLAY INVISIBLE (-1825 1450);
FORCEADD OFFPAGE..2
(-2000 1625);
FORCEPROP 2 LAST $XR0 53 
J 0
(-1811 1625);
DISPLAY 0.638298 (-1811 1625);
PAINT MONO (-1811 1625);
FORCEPROP 2 LAST $XR1 54 
J 0
(-1721 1625);
DISPLAY 0.638298 (-1721 1625);
PAINT MONO (-1721 1625);
FORCEPROP 2 LAST CDS_LIB mstr_standard
J 0
(-2000 1625);
PAINT MONO (-2000 1625);
DISPLAY INVISIBLE (-2000 1625);
FORCEPROP 1 LAST OFFPAGE TRUE
J 0
(-1675 1500);
DISPLAY 1.170213 (-1675 1500);
PAINT GREEN (-1675 1500);
DISPLAY INVISIBLE (-1675 1500);
FORCEPROP 1 LAST COMMENT_BODY TRUE
J 0
(-2045 1530);
DISPLAY 1.170213 (-2045 1530);
PAINT GREEN (-2045 1530);
DISPLAY INVISIBLE (-2045 1530);
FORCEPROP 2 LAST PATH I154
J 0
(-1825 1700);
DISPLAY 1.021277 (-1825 1700);
PAINT ORANGE (-1825 1700);
DISPLAY INVISIBLE (-1825 1700);
FORCEADD OFFPAGE..2
(-2000 1875);
FORCEPROP 2 LAST $XR0 53 
J 0
(-1811 1875);
DISPLAY 0.638298 (-1811 1875);
PAINT MONO (-1811 1875);
FORCEPROP 2 LAST $XR1 54 
J 0
(-1721 1875);
DISPLAY 0.638298 (-1721 1875);
PAINT MONO (-1721 1875);
FORCEPROP 2 LAST CDS_LIB mstr_standard
J 0
(-2000 1875);
PAINT MONO (-2000 1875);
DISPLAY INVISIBLE (-2000 1875);
FORCEPROP 1 LAST OFFPAGE TRUE
J 0
(-1675 1750);
DISPLAY 1.170213 (-1675 1750);
PAINT GREEN (-1675 1750);
DISPLAY INVISIBLE (-1675 1750);
FORCEPROP 1 LAST COMMENT_BODY TRUE
J 0
(-2045 1780);
DISPLAY 1.170213 (-2045 1780);
PAINT GREEN (-2045 1780);
DISPLAY INVISIBLE (-2045 1780);
FORCEPROP 2 LAST PATH I155
J 0
(-1825 1950);
DISPLAY 1.021277 (-1825 1950);
PAINT ORANGE (-1825 1950);
DISPLAY INVISIBLE (-1825 1950);
FORCEADD OFFPAGE..2
(-2000 2825);
FORCEPROP 2 LAST $XR0 53 
J 0
(-1811 2825);
DISPLAY 0.638298 (-1811 2825);
PAINT MONO (-1811 2825);
FORCEPROP 2 LAST $XR1 54 
J 0
(-1721 2825);
DISPLAY 0.638298 (-1721 2825);
PAINT MONO (-1721 2825);
FORCEPROP 2 LAST CDS_LIB mstr_standard
J 0
(-2000 2825);
PAINT MONO (-2000 2825);
DISPLAY INVISIBLE (-2000 2825);
FORCEPROP 1 LAST OFFPAGE TRUE
J 0
(-1675 2700);
DISPLAY 1.170213 (-1675 2700);
PAINT GREEN (-1675 2700);
DISPLAY INVISIBLE (-1675 2700);
FORCEPROP 1 LAST COMMENT_BODY TRUE
J 0
(-2045 2730);
DISPLAY 1.170213 (-2045 2730);
PAINT GREEN (-2045 2730);
DISPLAY INVISIBLE (-2045 2730);
FORCEPROP 2 LAST PATH I156
J 0
(-1825 2900);
DISPLAY 1.021277 (-1825 2900);
PAINT ORANGE (-1825 2900);
DISPLAY INVISIBLE (-1825 2900);
FORCEADD OFFPAGE..3
(-2000 3775);
FORCEPROP 2 LAST $XR0 53 
J 0
(-1786 3775);
DISPLAY 0.638298 (-1786 3775);
PAINT MONO (-1786 3775);
FORCEPROP 2 LAST $XR1 54 
J 0
(-1696 3775);
DISPLAY 0.638298 (-1696 3775);
PAINT MONO (-1696 3775);
FORCEPROP 2 LAST CDS_LIB mstr_standard
J 0
(-2000 3775);
PAINT MONO (-2000 3775);
DISPLAY INVISIBLE (-2000 3775);
FORCEPROP 1 LAST OFFPAGE TRUE
J 0
(-1675 3650);
DISPLAY 1.170213 (-1675 3650);
PAINT GREEN (-1675 3650);
DISPLAY INVISIBLE (-1675 3650);
FORCEPROP 1 LAST COMMENT_BODY TRUE
J 0
(-2050 3675);
DISPLAY 1.170213 (-2050 3675);
PAINT GREEN (-2050 3675);
DISPLAY INVISIBLE (-2050 3675);
FORCEPROP 2 LAST PATH I157
J 0
(-1800 3850);
DISPLAY 1.021277 (-1800 3850);
PAINT ORANGE (-1800 3850);
DISPLAY INVISIBLE (-1800 3850);
FORCEADD TAP..6
R 2
(-2850 4125);
FORCEPROP 3 LASTPIN (-2900 4125) SIG_NAME M_F_DQS_DP<6>
J 0
(-2890 4135);
DISPLAY 0.659574 (-2890 4135);
PAINT MONO (-2890 4135);
DISPLAY INVISIBLE (-2890 4135);
FORCEPROP 1 LASTPIN (-2900 4125) BN 6
J 2
(-2848 4133);
DISPLAY 0.617021 (-2848 4133);
PAINT PINK (-2848 4133);
FORCEPROP 2 LAST CDS_LIB mstr_standard
J 0
(-2850 4125);
PAINT MONO (-2850 4125);
DISPLAY INVISIBLE (-2850 4125);
FORCEPROP 1 LAST BODY_TYPE PLUMBING
J 2
(-2850 4075);
DISPLAY 1.595745 (-2850 4075);
PAINT GREEN (-2850 4075);
DISPLAY INVISIBLE (-2850 4075);
FORCEPROP 1 LAST HDL_TAP TRUE
J 2
(-3175 4000);
DISPLAY 1.595745 (-3175 4000);
PAINT GREEN (-3175 4000);
DISPLAY INVISIBLE (-3175 4000);
FORCEPROP 1 LAST PATH I158
J 2
(-2848 4125);
DISPLAY 0.872340 (-2848 4125);
PAINT GREEN (-2848 4125);
DISPLAY INVISIBLE (-2848 4125);
FORCEADD TAP..6
R 2
(-2850 4075);
FORCEPROP 3 LASTPIN (-2900 4075) SIG_NAME M_F_DQS_DP<5>
J 0
(-2890 4085);
DISPLAY 0.659574 (-2890 4085);
PAINT MONO (-2890 4085);
DISPLAY INVISIBLE (-2890 4085);
FORCEPROP 1 LASTPIN (-2900 4075) BN 5
J 2
(-2848 4083);
DISPLAY 0.617021 (-2848 4083);
PAINT PINK (-2848 4083);
FORCEPROP 2 LAST CDS_LIB mstr_standard
J 0
(-2850 4075);
PAINT MONO (-2850 4075);
DISPLAY INVISIBLE (-2850 4075);
FORCEPROP 1 LAST BODY_TYPE PLUMBING
J 2
(-2850 4025);
DISPLAY 1.595745 (-2850 4025);
PAINT GREEN (-2850 4025);
DISPLAY INVISIBLE (-2850 4025);
FORCEPROP 1 LAST HDL_TAP TRUE
J 2
(-3175 3950);
DISPLAY 1.595745 (-3175 3950);
PAINT GREEN (-3175 3950);
DISPLAY INVISIBLE (-3175 3950);
FORCEPROP 1 LAST PATH I159
J 2
(-2848 4075);
DISPLAY 0.872340 (-2848 4075);
PAINT GREEN (-2848 4075);
DISPLAY INVISIBLE (-2848 4075);
FORCEADD TAP..6
(-5575 1225);
FORCEPROP 3 LASTPIN (-5525 1225) SIG_NAME M_F_ECC<3>
J 0
(-5515 1235);
DISPLAY 0.659574 (-5515 1235);
PAINT MONO (-5515 1235);
DISPLAY INVISIBLE (-5515 1235);
FORCEPROP 1 LASTPIN (-5525 1225) BN 3
J 0
(-5577 1233);
DISPLAY 0.617021 (-5577 1233);
PAINT PINK (-5577 1233);
FORCEPROP 2 LAST CDS_LIB mstr_standard
J 0
(-5575 1225);
PAINT MONO (-5575 1225);
DISPLAY INVISIBLE (-5575 1225);
FORCEPROP 1 LAST BODY_TYPE PLUMBING
J 0
(-5575 1175);
DISPLAY 1.595745 (-5575 1175);
PAINT GREEN (-5575 1175);
DISPLAY INVISIBLE (-5575 1175);
FORCEPROP 1 LAST HDL_TAP TRUE
J 0
(-5250 1100);
DISPLAY 1.595745 (-5250 1100);
PAINT GREEN (-5250 1100);
DISPLAY INVISIBLE (-5250 1100);
FORCEPROP 1 LAST PATH I16
J 0
(-5577 1225);
DISPLAY 0.872340 (-5577 1225);
PAINT GREEN (-5577 1225);
DISPLAY INVISIBLE (-5577 1225);
FORCEADD TAP..6
R 2
(-2850 4175);
FORCEPROP 3 LASTPIN (-2900 4175) SIG_NAME M_F_DQS_DP<7>
J 0
(-2890 4185);
DISPLAY 0.659574 (-2890 4185);
PAINT MONO (-2890 4185);
DISPLAY INVISIBLE (-2890 4185);
FORCEPROP 1 LASTPIN (-2900 4175) BN 7
J 2
(-2848 4183);
DISPLAY 0.617021 (-2848 4183);
PAINT PINK (-2848 4183);
FORCEPROP 2 LAST CDS_LIB mstr_standard
J 0
(-2850 4175);
PAINT MONO (-2850 4175);
DISPLAY INVISIBLE (-2850 4175);
FORCEPROP 1 LAST BODY_TYPE PLUMBING
J 2
(-2850 4125);
DISPLAY 1.595745 (-2850 4125);
PAINT GREEN (-2850 4125);
DISPLAY INVISIBLE (-2850 4125);
FORCEPROP 1 LAST HDL_TAP TRUE
J 2
(-3175 4050);
DISPLAY 1.595745 (-3175 4050);
PAINT GREEN (-3175 4050);
DISPLAY INVISIBLE (-3175 4050);
FORCEPROP 1 LAST PATH I160
J 2
(-2848 4175);
DISPLAY 0.872340 (-2848 4175);
PAINT GREEN (-2848 4175);
DISPLAY INVISIBLE (-2848 4175);
FORCEADD TAP..6
R 2
(-2850 4275);
FORCEPROP 3 LASTPIN (-2900 4275) SIG_NAME M_F_DQS_DP<9>
J 0
(-2890 4285);
DISPLAY 0.659574 (-2890 4285);
PAINT MONO (-2890 4285);
DISPLAY INVISIBLE (-2890 4285);
FORCEPROP 1 LASTPIN (-2900 4275) BN 9
J 2
(-2848 4283);
DISPLAY 0.617021 (-2848 4283);
PAINT PINK (-2848 4283);
FORCEPROP 2 LAST CDS_LIB mstr_standard
J 0
(-2850 4275);
PAINT MONO (-2850 4275);
DISPLAY INVISIBLE (-2850 4275);
FORCEPROP 1 LAST BODY_TYPE PLUMBING
J 2
(-2850 4225);
DISPLAY 1.595745 (-2850 4225);
PAINT GREEN (-2850 4225);
DISPLAY INVISIBLE (-2850 4225);
FORCEPROP 1 LAST HDL_TAP TRUE
J 2
(-3175 4150);
DISPLAY 1.595745 (-3175 4150);
PAINT GREEN (-3175 4150);
DISPLAY INVISIBLE (-3175 4150);
FORCEPROP 1 LAST PATH I161
J 2
(-2848 4275);
DISPLAY 0.872340 (-2848 4275);
PAINT GREEN (-2848 4275);
DISPLAY INVISIBLE (-2848 4275);
FORCEADD TAP..6
R 2
(-2850 4225);
FORCEPROP 3 LASTPIN (-2900 4225) SIG_NAME M_F_DQS_DP<8>
J 0
(-2890 4235);
DISPLAY 0.659574 (-2890 4235);
PAINT MONO (-2890 4235);
DISPLAY INVISIBLE (-2890 4235);
FORCEPROP 1 LASTPIN (-2900 4225) BN 8
J 2
(-2848 4233);
DISPLAY 0.617021 (-2848 4233);
PAINT PINK (-2848 4233);
FORCEPROP 2 LAST CDS_LIB mstr_standard
J 0
(-2850 4225);
PAINT MONO (-2850 4225);
DISPLAY INVISIBLE (-2850 4225);
FORCEPROP 1 LAST BODY_TYPE PLUMBING
J 2
(-2850 4175);
DISPLAY 1.595745 (-2850 4175);
PAINT GREEN (-2850 4175);
DISPLAY INVISIBLE (-2850 4175);
FORCEPROP 1 LAST HDL_TAP TRUE
J 2
(-3175 4100);
DISPLAY 1.595745 (-3175 4100);
PAINT GREEN (-3175 4100);
DISPLAY INVISIBLE (-3175 4100);
FORCEPROP 1 LAST PATH I162
J 2
(-2848 4225);
DISPLAY 0.872340 (-2848 4225);
PAINT GREEN (-2848 4225);
DISPLAY INVISIBLE (-2848 4225);
FORCEADD TAP..6
R 2
(-2850 4425);
FORCEPROP 3 LASTPIN (-2900 4425) SIG_NAME M_F_DQS_DP<12>
J 0
(-2890 4435);
DISPLAY 0.659574 (-2890 4435);
PAINT MONO (-2890 4435);
DISPLAY INVISIBLE (-2890 4435);
FORCEPROP 1 LASTPIN (-2900 4425) BN 12
J 2
(-2848 4433);
DISPLAY 0.617021 (-2848 4433);
PAINT PINK (-2848 4433);
FORCEPROP 2 LAST CDS_LIB mstr_standard
J 0
(-2850 4425);
PAINT MONO (-2850 4425);
DISPLAY INVISIBLE (-2850 4425);
FORCEPROP 1 LAST BODY_TYPE PLUMBING
J 2
(-2850 4375);
DISPLAY 1.595745 (-2850 4375);
PAINT GREEN (-2850 4375);
DISPLAY INVISIBLE (-2850 4375);
FORCEPROP 1 LAST HDL_TAP TRUE
J 2
(-3175 4300);
DISPLAY 1.595745 (-3175 4300);
PAINT GREEN (-3175 4300);
DISPLAY INVISIBLE (-3175 4300);
FORCEPROP 1 LAST PATH I163
J 2
(-2848 4425);
DISPLAY 0.872340 (-2848 4425);
PAINT GREEN (-2848 4425);
DISPLAY INVISIBLE (-2848 4425);
FORCEADD TAP..6
R 2
(-2850 4375);
FORCEPROP 3 LASTPIN (-2900 4375) SIG_NAME M_F_DQS_DP<11>
J 0
(-2890 4385);
DISPLAY 0.659574 (-2890 4385);
PAINT MONO (-2890 4385);
DISPLAY INVISIBLE (-2890 4385);
FORCEPROP 1 LASTPIN (-2900 4375) BN 11
J 2
(-2848 4383);
DISPLAY 0.617021 (-2848 4383);
PAINT PINK (-2848 4383);
FORCEPROP 2 LAST CDS_LIB mstr_standard
J 0
(-2850 4375);
PAINT MONO (-2850 4375);
DISPLAY INVISIBLE (-2850 4375);
FORCEPROP 1 LAST BODY_TYPE PLUMBING
J 2
(-2850 4325);
DISPLAY 1.595745 (-2850 4325);
PAINT GREEN (-2850 4325);
DISPLAY INVISIBLE (-2850 4325);
FORCEPROP 1 LAST HDL_TAP TRUE
J 2
(-3175 4250);
DISPLAY 1.595745 (-3175 4250);
PAINT GREEN (-3175 4250);
DISPLAY INVISIBLE (-3175 4250);
FORCEPROP 1 LAST PATH I164
J 2
(-2848 4375);
DISPLAY 0.872340 (-2848 4375);
PAINT GREEN (-2848 4375);
DISPLAY INVISIBLE (-2848 4375);
FORCEADD TAP..6
R 2
(-2850 4325);
FORCEPROP 3 LASTPIN (-2900 4325) SIG_NAME M_F_DQS_DP<10>
J 0
(-2890 4335);
DISPLAY 0.659574 (-2890 4335);
PAINT MONO (-2890 4335);
DISPLAY INVISIBLE (-2890 4335);
FORCEPROP 1 LASTPIN (-2900 4325) BN 10
J 2
(-2848 4333);
DISPLAY 0.617021 (-2848 4333);
PAINT PINK (-2848 4333);
FORCEPROP 2 LAST CDS_LIB mstr_standard
J 0
(-2850 4325);
PAINT MONO (-2850 4325);
DISPLAY INVISIBLE (-2850 4325);
FORCEPROP 1 LAST BODY_TYPE PLUMBING
J 2
(-2850 4275);
DISPLAY 1.595745 (-2850 4275);
PAINT GREEN (-2850 4275);
DISPLAY INVISIBLE (-2850 4275);
FORCEPROP 1 LAST HDL_TAP TRUE
J 2
(-3175 4200);
DISPLAY 1.595745 (-3175 4200);
PAINT GREEN (-3175 4200);
DISPLAY INVISIBLE (-3175 4200);
FORCEPROP 1 LAST PATH I165
J 2
(-2848 4325);
DISPLAY 0.872340 (-2848 4325);
PAINT GREEN (-2848 4325);
DISPLAY INVISIBLE (-2848 4325);
FORCEADD TAP..6
R 2
(-2850 4475);
FORCEPROP 3 LASTPIN (-2900 4475) SIG_NAME M_F_DQS_DP<13>
J 0
(-2890 4485);
DISPLAY 0.659574 (-2890 4485);
PAINT MONO (-2890 4485);
DISPLAY INVISIBLE (-2890 4485);
FORCEPROP 1 LASTPIN (-2900 4475) BN 13
J 2
(-2848 4483);
DISPLAY 0.617021 (-2848 4483);
PAINT PINK (-2848 4483);
FORCEPROP 2 LAST CDS_LIB mstr_standard
J 0
(-2850 4475);
PAINT MONO (-2850 4475);
DISPLAY INVISIBLE (-2850 4475);
FORCEPROP 1 LAST BODY_TYPE PLUMBING
J 2
(-2850 4425);
DISPLAY 1.595745 (-2850 4425);
PAINT GREEN (-2850 4425);
DISPLAY INVISIBLE (-2850 4425);
FORCEPROP 1 LAST HDL_TAP TRUE
J 2
(-3175 4350);
DISPLAY 1.595745 (-3175 4350);
PAINT GREEN (-3175 4350);
DISPLAY INVISIBLE (-3175 4350);
FORCEPROP 1 LAST PATH I166
J 2
(-2848 4475);
DISPLAY 0.872340 (-2848 4475);
PAINT GREEN (-2848 4475);
DISPLAY INVISIBLE (-2848 4475);
FORCEADD TAP..6
R 2
(-2850 4525);
FORCEPROP 3 LASTPIN (-2900 4525) SIG_NAME M_F_DQS_DP<14>
J 0
(-2890 4535);
DISPLAY 0.659574 (-2890 4535);
PAINT MONO (-2890 4535);
DISPLAY INVISIBLE (-2890 4535);
FORCEPROP 1 LASTPIN (-2900 4525) BN 14
J 2
(-2848 4533);
DISPLAY 0.617021 (-2848 4533);
PAINT PINK (-2848 4533);
FORCEPROP 2 LAST CDS_LIB mstr_standard
J 0
(-2850 4525);
PAINT MONO (-2850 4525);
DISPLAY INVISIBLE (-2850 4525);
FORCEPROP 1 LAST BODY_TYPE PLUMBING
J 2
(-2850 4475);
DISPLAY 1.595745 (-2850 4475);
PAINT GREEN (-2850 4475);
DISPLAY INVISIBLE (-2850 4475);
FORCEPROP 1 LAST HDL_TAP TRUE
J 2
(-3175 4400);
DISPLAY 1.595745 (-3175 4400);
PAINT GREEN (-3175 4400);
DISPLAY INVISIBLE (-3175 4400);
FORCEPROP 1 LAST PATH I167
J 2
(-2848 4525);
DISPLAY 0.872340 (-2848 4525);
PAINT GREEN (-2848 4525);
DISPLAY INVISIBLE (-2848 4525);
FORCEADD TAP..6
R 2
(-2850 4575);
FORCEPROP 3 LASTPIN (-2900 4575) SIG_NAME M_F_DQS_DP<15>
J 0
(-2890 4585);
DISPLAY 0.659574 (-2890 4585);
PAINT MONO (-2890 4585);
DISPLAY INVISIBLE (-2890 4585);
FORCEPROP 1 LASTPIN (-2900 4575) BN 15
J 2
(-2848 4583);
DISPLAY 0.617021 (-2848 4583);
PAINT PINK (-2848 4583);
FORCEPROP 2 LAST CDS_LIB mstr_standard
J 0
(-2850 4575);
PAINT MONO (-2850 4575);
DISPLAY INVISIBLE (-2850 4575);
FORCEPROP 1 LAST BODY_TYPE PLUMBING
J 2
(-2850 4525);
DISPLAY 1.595745 (-2850 4525);
PAINT GREEN (-2850 4525);
DISPLAY INVISIBLE (-2850 4525);
FORCEPROP 1 LAST HDL_TAP TRUE
J 2
(-3175 4450);
DISPLAY 1.595745 (-3175 4450);
PAINT GREEN (-3175 4450);
DISPLAY INVISIBLE (-3175 4450);
FORCEPROP 1 LAST PATH I168
J 2
(-2848 4575);
DISPLAY 0.872340 (-2848 4575);
PAINT GREEN (-2848 4575);
DISPLAY INVISIBLE (-2848 4575);
FORCEADD TAP..6
R 2
(-2850 4625);
FORCEPROP 3 LASTPIN (-2900 4625) SIG_NAME M_F_DQS_DP<16>
J 0
(-2890 4635);
DISPLAY 0.659574 (-2890 4635);
PAINT MONO (-2890 4635);
DISPLAY INVISIBLE (-2890 4635);
FORCEPROP 1 LASTPIN (-2900 4625) BN 16
J 2
(-2848 4633);
DISPLAY 0.617021 (-2848 4633);
PAINT PINK (-2848 4633);
FORCEPROP 2 LAST CDS_LIB mstr_standard
J 0
(-2850 4625);
PAINT MONO (-2850 4625);
DISPLAY INVISIBLE (-2850 4625);
FORCEPROP 1 LAST BODY_TYPE PLUMBING
J 2
(-2850 4575);
DISPLAY 1.595745 (-2850 4575);
PAINT GREEN (-2850 4575);
DISPLAY INVISIBLE (-2850 4575);
FORCEPROP 1 LAST HDL_TAP TRUE
J 2
(-3175 4500);
DISPLAY 1.595745 (-3175 4500);
PAINT GREEN (-3175 4500);
DISPLAY INVISIBLE (-3175 4500);
FORCEPROP 1 LAST PATH I169
J 2
(-2848 4625);
DISPLAY 0.872340 (-2848 4625);
PAINT GREEN (-2848 4625);
DISPLAY INVISIBLE (-2848 4625);
FORCEADD TAP..6
(-5575 1275);
FORCEPROP 3 LASTPIN (-5525 1275) SIG_NAME M_F_ECC<4>
J 0
(-5515 1285);
DISPLAY 0.659574 (-5515 1285);
PAINT MONO (-5515 1285);
DISPLAY INVISIBLE (-5515 1285);
FORCEPROP 1 LASTPIN (-5525 1275) BN 4
J 0
(-5577 1283);
DISPLAY 0.617021 (-5577 1283);
PAINT PINK (-5577 1283);
FORCEPROP 2 LAST CDS_LIB mstr_standard
J 0
(-5575 1275);
PAINT MONO (-5575 1275);
DISPLAY INVISIBLE (-5575 1275);
FORCEPROP 1 LAST BODY_TYPE PLUMBING
J 0
(-5575 1225);
DISPLAY 1.595745 (-5575 1225);
PAINT GREEN (-5575 1225);
DISPLAY INVISIBLE (-5575 1225);
FORCEPROP 1 LAST HDL_TAP TRUE
J 0
(-5250 1150);
DISPLAY 1.595745 (-5250 1150);
PAINT GREEN (-5250 1150);
DISPLAY INVISIBLE (-5250 1150);
FORCEPROP 1 LAST PATH I17
J 0
(-5577 1275);
DISPLAY 0.872340 (-5577 1275);
PAINT GREEN (-5577 1275);
DISPLAY INVISIBLE (-5577 1275);
FORCEADD TAP..6
R 2
(-2850 4675);
FORCEPROP 3 LASTPIN (-2900 4675) SIG_NAME M_F_DQS_DP<17>
J 0
(-2890 4685);
DISPLAY 0.659574 (-2890 4685);
PAINT MONO (-2890 4685);
DISPLAY INVISIBLE (-2890 4685);
FORCEPROP 1 LASTPIN (-2900 4675) BN 17
J 2
(-2848 4683);
DISPLAY 0.617021 (-2848 4683);
PAINT PINK (-2848 4683);
FORCEPROP 2 LAST CDS_LIB mstr_standard
J 2
(-2850 4675);
PAINT MONO (-2850 4675);
DISPLAY INVISIBLE (-2850 4675);
FORCEPROP 1 LAST BODY_TYPE PLUMBING
J 2
(-2850 4625);
DISPLAY 1.595745 (-2850 4625);
PAINT GREEN (-2850 4625);
DISPLAY INVISIBLE (-2850 4625);
FORCEPROP 1 LAST HDL_TAP TRUE
J 2
(-3175 4550);
DISPLAY 1.595745 (-3175 4550);
PAINT GREEN (-3175 4550);
DISPLAY INVISIBLE (-3175 4550);
FORCEPROP 1 LAST PATH I170
J 2
(-2848 4675);
DISPLAY 0.872340 (-2848 4675);
PAINT GREEN (-2848 4675);
DISPLAY INVISIBLE (-2848 4675);
FORCEADD OFFPAGE..3
(-2000 4750);
FORCEPROP 2 LAST $XR0 53 
J 0
(-1786 4750);
DISPLAY 0.638298 (-1786 4750);
PAINT MONO (-1786 4750);
FORCEPROP 2 LAST $XR1 54 
J 0
(-1696 4750);
DISPLAY 0.638298 (-1696 4750);
PAINT MONO (-1696 4750);
FORCEPROP 2 LAST CDS_LIB mstr_standard
J 0
(-2000 4750);
PAINT MONO (-2000 4750);
DISPLAY INVISIBLE (-2000 4750);
FORCEPROP 1 LAST OFFPAGE TRUE
J 0
(-1675 4625);
DISPLAY 1.170213 (-1675 4625);
PAINT GREEN (-1675 4625);
DISPLAY INVISIBLE (-1675 4625);
FORCEPROP 1 LAST COMMENT_BODY TRUE
J 0
(-2050 4650);
DISPLAY 1.170213 (-2050 4650);
PAINT GREEN (-2050 4650);
DISPLAY INVISIBLE (-2050 4650);
FORCEPROP 2 LAST PATH I171
J 0
(-1800 4825);
DISPLAY 1.021277 (-1800 4825);
PAINT ORANGE (-1800 4825);
DISPLAY INVISIBLE (-1800 4825);
FORCEADD SKX_EXT_B..8
(-4175 2575);
FORCEPROP 1 LAST LOCATION U5D1
J 0
(-4975 4925);
DISPLAY 0.617021 (-4975 4925);
PAINT AQUA (-4975 4925);
FORCEPROP 1 LAST PART_NUMBER TBD
J 0
(-4975 325);
DISPLAY 0.617021 (-4975 325);
PAINT BLUE (-4975 325);
FORCEPROP 1 LAST MATERIAL IC
J 0
(-4975 4875);
DISPLAY 0.617021 (-4975 4875);
PAINT SKYBLUE (-4975 4875);
FORCEPROP 2 LASTPIN (-3325 525) $PN DK53
J 0
(-3315 535);
DISPLAY 0.617021 (-3315 535);
PAINT ORANGE (-3315 535);
FORCEPROP 2 LASTPIN (-3325 1575) $PN DF47
J 0
(-3315 1585);
DISPLAY 0.617021 (-3315 1585);
PAINT ORANGE (-3315 1585);
FORCEPROP 2 LASTPIN (-3325 1525) $PN DK49
J 0
(-3315 1535);
DISPLAY 0.617021 (-3315 1535);
PAINT ORANGE (-3315 1535);
FORCEPROP 2 LASTPIN (-3325 1475) $PN DG48
J 0
(-3315 1485);
DISPLAY 0.617021 (-3315 1485);
PAINT ORANGE (-3315 1485);
FORCEPROP 2 LASTPIN (-3325 1425) $PN DG50
J 0
(-3315 1435);
DISPLAY 0.617021 (-3315 1435);
PAINT ORANGE (-3315 1435);
FORCEPROP 2 LASTPIN (-3325 2775) $PN DE46
J 0
(-3315 2785);
DISPLAY 0.617021 (-3315 2785);
PAINT ORANGE (-3315 2785);
FORCEPROP 2 LASTPIN (-3325 2725) $PN DG52
J 0
(-3315 2735);
DISPLAY 0.617021 (-3315 2735);
PAINT ORANGE (-3315 2735);
FORCEPROP 2 LASTPIN (-3325 2675) $PN DC54
J 0
(-3315 2685);
DISPLAY 0.617021 (-3315 2685);
PAINT ORANGE (-3315 2685);
FORCEPROP 2 LASTPIN (-3325 2625) $PN DJ50
J 0
(-3315 2635);
DISPLAY 0.617021 (-3315 2635);
PAINT ORANGE (-3315 2635);
FORCEPROP 2 LASTPIN (-3325 2575) $PN DD53
J 0
(-3315 2585);
DISPLAY 0.617021 (-3315 2585);
PAINT ORANGE (-3315 2585);
FORCEPROP 2 LASTPIN (-3325 2525) $PN DG60
J 0
(-3315 2535);
DISPLAY 0.617021 (-3315 2535);
PAINT ORANGE (-3315 2535);
FORCEPROP 2 LASTPIN (-3325 2475) $PN DA60
J 0
(-3315 2485);
DISPLAY 0.617021 (-3315 2485);
PAINT ORANGE (-3315 2485);
FORCEPROP 2 LASTPIN (-3325 2425) $PN DD55
J 0
(-3315 2435);
DISPLAY 0.617021 (-3315 2435);
PAINT ORANGE (-3315 2435);
FORCEPROP 2 LASTPIN (-3325 2375) $PN DA58
J 0
(-3315 2385);
DISPLAY 0.617021 (-3315 2385);
PAINT ORANGE (-3315 2385);
FORCEPROP 2 LASTPIN (-3325 2325) $PN DD59
J 0
(-3315 2335);
DISPLAY 0.617021 (-3315 2335);
PAINT ORANGE (-3315 2335);
FORCEPROP 2 LASTPIN (-3325 2275) $PN DC60
J 0
(-3315 2285);
DISPLAY 0.617021 (-3315 2285);
PAINT ORANGE (-3315 2285);
FORCEPROP 2 LASTPIN (-3325 2225) $PN DK59
J 0
(-3315 2235);
DISPLAY 0.617021 (-3315 2235);
PAINT ORANGE (-3315 2235);
FORCEPROP 2 LASTPIN (-3325 2175) $PN DF59
J 0
(-3315 2185);
DISPLAY 0.617021 (-3315 2185);
PAINT ORANGE (-3315 2185);
FORCEPROP 2 LASTPIN (-3325 2125) $PN DJ58
J 0
(-3315 2135);
DISPLAY 0.617021 (-3315 2135);
PAINT ORANGE (-3315 2135);
FORCEPROP 2 LASTPIN (-3325 2075) $PN DG58
J 0
(-3315 2085);
DISPLAY 0.617021 (-3315 2085);
PAINT ORANGE (-3315 2085);
FORCEPROP 2 LASTPIN (-3325 2025) $PN DD57
J 0
(-3315 2035);
DISPLAY 0.617021 (-3315 2035);
PAINT ORANGE (-3315 2035);
FORCEPROP 2 LASTPIN (-3325 1975) $PN DC58
J 0
(-3315 1985);
DISPLAY 0.617021 (-3315 1985);
PAINT ORANGE (-3315 1985);
FORCEPROP 2 LASTPIN (-3325 1925) $PN DF53
J 0
(-3315 1935);
DISPLAY 0.617021 (-3315 1935);
PAINT ORANGE (-3315 1935);
FORCEPROP 2 LASTPIN (-5025 1425) $PN CM69
J 2
(-5035 1435);
DISPLAY 0.617021 (-5035 1435);
PAINT ORANGE (-5035 1435);
FORCEPROP 2 LASTPIN (-5025 1375) $PN CH69
J 2
(-5035 1385);
DISPLAY 0.617021 (-5035 1385);
PAINT ORANGE (-5035 1385);
FORCEPROP 2 LASTPIN (-5025 1325) $PN CL72
J 2
(-5035 1335);
DISPLAY 0.617021 (-5035 1335);
PAINT ORANGE (-5035 1335);
FORCEPROP 2 LASTPIN (-5025 1275) $PN CJ72
J 2
(-5035 1285);
DISPLAY 0.617021 (-5035 1285);
PAINT ORANGE (-5035 1285);
FORCEPROP 2 LASTPIN (-5025 1225) $PN CL68
J 2
(-5035 1235);
DISPLAY 0.617021 (-5035 1235);
PAINT ORANGE (-5035 1235);
FORCEPROP 2 LASTPIN (-5025 1175) $PN CJ68
J 2
(-5035 1185);
DISPLAY 0.617021 (-5035 1185);
PAINT ORANGE (-5035 1185);
FORCEPROP 2 LASTPIN (-5025 1125) $PN CM71
J 2
(-5035 1135);
DISPLAY 0.617021 (-5035 1135);
PAINT ORANGE (-5035 1135);
FORCEPROP 2 LASTPIN (-5025 1075) $PN CH71
J 2
(-5035 1085);
DISPLAY 0.617021 (-5035 1085);
PAINT ORANGE (-5035 1085);
FORCEPROP 2 LASTPIN (-3325 4675) $PN CG70
J 0
(-3315 4685);
DISPLAY 0.617021 (-3315 4685);
PAINT ORANGE (-3315 4685);
FORCEPROP 2 LASTPIN (-3325 4625) $PN CV29
J 0
(-3315 4635);
DISPLAY 0.617021 (-3315 4635);
PAINT ORANGE (-3315 4635);
FORCEPROP 2 LASTPIN (-3325 4575) $PN CV35
J 0
(-3315 4585);
DISPLAY 0.617021 (-3315 4585);
PAINT ORANGE (-3315 4585);
FORCEPROP 2 LASTPIN (-3325 4525) $PN DE32
J 0
(-3315 4535);
DISPLAY 0.617021 (-3315 4535);
PAINT ORANGE (-3315 4535);
FORCEPROP 2 LASTPIN (-3325 4475) $PN DC40
J 0
(-3315 4485);
DISPLAY 0.617021 (-3315 4485);
PAINT ORANGE (-3315 4485);
FORCEPROP 2 LASTPIN (-3325 4425) $PN CM65
J 0
(-3315 4435);
DISPLAY 0.617021 (-3315 4435);
PAINT ORANGE (-3315 4435);
FORCEPROP 2 LASTPIN (-3325 4375) $PN DH69
J 0
(-3315 4385);
DISPLAY 0.617021 (-3315 4385);
PAINT ORANGE (-3315 4385);
FORCEPROP 2 LASTPIN (-3325 4325) $PN DG74
J 0
(-3315 4335);
DISPLAY 0.617021 (-3315 4335);
PAINT ORANGE (-3315 4335);
FORCEPROP 2 LASTPIN (-3325 4275) $PN CU74
J 0
(-3315 4285);
DISPLAY 0.617021 (-3315 4285);
PAINT ORANGE (-3315 4285);
FORCEPROP 2 LASTPIN (-3325 4225) $PN CL70
J 0
(-3315 4235);
DISPLAY 0.617021 (-3315 4235);
PAINT ORANGE (-3315 4235);
FORCEPROP 2 LASTPIN (-3325 4175) $PN DB29
J 0
(-3315 4185);
DISPLAY 0.617021 (-3315 4185);
PAINT ORANGE (-3315 4185);
FORCEPROP 2 LASTPIN (-3325 4125) $PN DB35
J 0
(-3315 4135);
DISPLAY 0.617021 (-3315 4135);
PAINT ORANGE (-3315 4135);
FORCEPROP 2 LASTPIN (-3325 4075) $PN DJ32
J 0
(-3315 4085);
DISPLAY 0.617021 (-3315 4085);
PAINT ORANGE (-3315 4085);
FORCEPROP 2 LASTPIN (-3325 4025) $PN DJ40
J 0
(-3315 4035);
DISPLAY 0.617021 (-3315 4035);
PAINT ORANGE (-3315 4035);
FORCEPROP 2 LASTPIN (-3325 3975) $PN CT65
J 0
(-3315 3985);
DISPLAY 0.617021 (-3315 3985);
PAINT ORANGE (-3315 3985);
FORCEPROP 2 LASTPIN (-3325 3925) $PN DK71
J 0
(-3315 3935);
DISPLAY 0.617021 (-3315 3935);
PAINT ORANGE (-3315 3935);
FORCEPROP 2 LASTPIN (-3325 3875) $PN DE76
J 0
(-3315 3885);
DISPLAY 0.617021 (-3315 3885);
PAINT ORANGE (-3315 3885);
FORCEPROP 2 LASTPIN (-3325 3825) $PN CR76
J 0
(-3315 3835);
DISPLAY 0.617021 (-3315 3835);
PAINT ORANGE (-3315 3835);
FORCEPROP 2 LASTPIN (-3325 3725) $PN CJ70
J 0
(-3315 3735);
DISPLAY 0.617021 (-3315 3735);
PAINT ORANGE (-3315 3735);
FORCEPROP 2 LASTPIN (-3325 3675) $PN CY29
J 0
(-3315 3685);
DISPLAY 0.617021 (-3315 3685);
PAINT ORANGE (-3315 3685);
FORCEPROP 2 LASTPIN (-3325 3625) $PN CY35
J 0
(-3315 3635);
DISPLAY 0.617021 (-3315 3635);
PAINT ORANGE (-3315 3635);
FORCEPROP 2 LASTPIN (-3325 3575) $PN DG32
J 0
(-3315 3585);
DISPLAY 0.617021 (-3315 3585);
PAINT ORANGE (-3315 3585);
FORCEPROP 2 LASTPIN (-3325 3525) $PN DE40
J 0
(-3315 3535);
DISPLAY 0.617021 (-3315 3535);
PAINT ORANGE (-3315 3535);
FORCEPROP 2 LASTPIN (-3325 3475) $PN CP65
J 0
(-3315 3485);
DISPLAY 0.617021 (-3315 3485);
PAINT ORANGE (-3315 3485);
FORCEPROP 2 LASTPIN (-3325 3425) $PN DJ70
J 0
(-3315 3435);
DISPLAY 0.617021 (-3315 3435);
PAINT ORANGE (-3315 3435);
FORCEPROP 2 LASTPIN (-3325 3375) $PN DF75
J 0
(-3315 3385);
DISPLAY 0.617021 (-3315 3385);
PAINT ORANGE (-3315 3385);
FORCEPROP 2 LASTPIN (-3325 3325) $PN CT75
J 0
(-3315 3335);
DISPLAY 0.617021 (-3315 3335);
PAINT ORANGE (-3315 3335);
FORCEPROP 2 LASTPIN (-3325 3275) $PN CN70
J 0
(-3315 3285);
DISPLAY 0.617021 (-3315 3285);
PAINT ORANGE (-3315 3285);
FORCEPROP 2 LASTPIN (-3325 3225) $PN DD29
J 0
(-3315 3235);
DISPLAY 0.617021 (-3315 3235);
PAINT ORANGE (-3315 3235);
FORCEPROP 2 LASTPIN (-3325 3175) $PN DD35
J 0
(-3315 3185);
DISPLAY 0.617021 (-3315 3185);
PAINT ORANGE (-3315 3185);
FORCEPROP 2 LASTPIN (-3325 3125) $PN DL32
J 0
(-3315 3135);
DISPLAY 0.617021 (-3315 3135);
PAINT ORANGE (-3315 3135);
FORCEPROP 2 LASTPIN (-3325 3075) $PN DG40
J 0
(-3315 3085);
DISPLAY 0.617021 (-3315 3085);
PAINT ORANGE (-3315 3085);
FORCEPROP 2 LASTPIN (-3325 3025) $PN CV65
J 0
(-3315 3035);
DISPLAY 0.617021 (-3315 3035);
PAINT ORANGE (-3315 3035);
FORCEPROP 2 LASTPIN (-3325 2975) $PN DL72
J 0
(-3315 2985);
DISPLAY 0.617021 (-3315 2985);
PAINT ORANGE (-3315 2985);
FORCEPROP 2 LASTPIN (-3325 2925) $PN DD77
J 0
(-3315 2935);
DISPLAY 0.617021 (-3315 2935);
PAINT ORANGE (-3315 2935);
FORCEPROP 2 LASTPIN (-3325 2875) $PN CP77
J 0
(-3315 2885);
DISPLAY 0.617021 (-3315 2885);
PAINT ORANGE (-3315 2885);
FORCEPROP 2 LASTPIN (-5025 4675) $PN DC28
J 2
(-5035 4685);
DISPLAY 0.617021 (-5035 4685);
PAINT ORANGE (-5035 4685);
FORCEPROP 2 LASTPIN (-5025 4625) $PN CW28
J 2
(-5035 4635);
DISPLAY 0.617021 (-5035 4635);
PAINT ORANGE (-5035 4635);
FORCEPROP 2 LASTPIN (-5025 4575) $PN DB31
J 2
(-5035 4585);
DISPLAY 0.617021 (-5035 4585);
PAINT ORANGE (-5035 4585);
FORCEPROP 2 LASTPIN (-5025 4525) $PN CY31
J 2
(-5035 4535);
DISPLAY 0.617021 (-5035 4535);
PAINT ORANGE (-5035 4535);
FORCEPROP 2 LASTPIN (-5025 4475) $PN DB27
J 2
(-5035 4485);
DISPLAY 0.617021 (-5035 4485);
PAINT ORANGE (-5035 4485);
FORCEPROP 2 LASTPIN (-5025 4425) $PN CY27
J 2
(-5035 4435);
DISPLAY 0.617021 (-5035 4435);
PAINT ORANGE (-5035 4435);
FORCEPROP 2 LASTPIN (-5025 4375) $PN DC30
J 2
(-5035 4385);
DISPLAY 0.617021 (-5035 4385);
PAINT ORANGE (-5035 4385);
FORCEPROP 2 LASTPIN (-5025 4325) $PN CW30
J 2
(-5035 4335);
DISPLAY 0.617021 (-5035 4335);
PAINT ORANGE (-5035 4335);
FORCEPROP 2 LASTPIN (-5025 4275) $PN DC34
J 2
(-5035 4285);
DISPLAY 0.617021 (-5035 4285);
PAINT ORANGE (-5035 4285);
FORCEPROP 2 LASTPIN (-5025 4225) $PN CW34
J 2
(-5035 4235);
DISPLAY 0.617021 (-5035 4235);
PAINT ORANGE (-5035 4235);
FORCEPROP 2 LASTPIN (-5025 4175) $PN DB37
J 2
(-5035 4185);
DISPLAY 0.617021 (-5035 4185);
PAINT ORANGE (-5035 4185);
FORCEPROP 2 LASTPIN (-5025 4125) $PN CY37
J 2
(-5035 4135);
DISPLAY 0.617021 (-5035 4135);
PAINT ORANGE (-5035 4135);
FORCEPROP 2 LASTPIN (-5025 4075) $PN DB33
J 2
(-5035 4085);
DISPLAY 0.617021 (-5035 4085);
PAINT ORANGE (-5035 4085);
FORCEPROP 2 LASTPIN (-5025 4025) $PN CY33
J 2
(-5035 4035);
DISPLAY 0.617021 (-5035 4035);
PAINT ORANGE (-5035 4035);
FORCEPROP 2 LASTPIN (-5025 3975) $PN DC36
J 2
(-5035 3985);
DISPLAY 0.617021 (-5035 3985);
PAINT ORANGE (-5035 3985);
FORCEPROP 2 LASTPIN (-5025 3925) $PN CW36
J 2
(-5035 3935);
DISPLAY 0.617021 (-5035 3935);
PAINT ORANGE (-5035 3935);
FORCEPROP 2 LASTPIN (-5025 3875) $PN DK31
J 2
(-5035 3885);
DISPLAY 0.617021 (-5035 3885);
PAINT ORANGE (-5035 3885);
FORCEPROP 2 LASTPIN (-5025 3825) $PN DF31
J 2
(-5035 3835);
DISPLAY 0.617021 (-5035 3835);
PAINT ORANGE (-5035 3835);
FORCEPROP 2 LASTPIN (-5025 3775) $PN DJ34
J 2
(-5035 3785);
DISPLAY 0.617021 (-5035 3785);
PAINT ORANGE (-5035 3785);
FORCEPROP 2 LASTPIN (-5025 3725) $PN DG34
J 2
(-5035 3735);
DISPLAY 0.617021 (-5035 3735);
PAINT ORANGE (-5035 3735);
FORCEPROP 2 LASTPIN (-5025 3675) $PN DJ30
J 2
(-5035 3685);
DISPLAY 0.617021 (-5035 3685);
PAINT ORANGE (-5035 3685);
FORCEPROP 2 LASTPIN (-5025 3625) $PN DG30
J 2
(-5035 3635);
DISPLAY 0.617021 (-5035 3635);
PAINT ORANGE (-5035 3635);
FORCEPROP 2 LASTPIN (-5025 3575) $PN DK33
J 2
(-5035 3585);
DISPLAY 0.617021 (-5035 3585);
PAINT ORANGE (-5035 3585);
FORCEPROP 2 LASTPIN (-5025 3525) $PN DF33
J 2
(-5035 3535);
DISPLAY 0.617021 (-5035 3535);
PAINT ORANGE (-5035 3535);
FORCEPROP 2 LASTPIN (-5025 3475) $PN DH39
J 2
(-5035 3485);
DISPLAY 0.617021 (-5035 3485);
PAINT ORANGE (-5035 3485);
FORCEPROP 2 LASTPIN (-5025 3425) $PN DD39
J 2
(-5035 3435);
DISPLAY 0.617021 (-5035 3435);
PAINT ORANGE (-5035 3435);
FORCEPROP 2 LASTPIN (-5025 3375) $PN DE42
J 2
(-5035 3385);
DISPLAY 0.617021 (-5035 3385);
PAINT ORANGE (-5035 3385);
FORCEPROP 2 LASTPIN (-5025 3325) $PN DA42
J 2
(-5035 3335);
DISPLAY 0.617021 (-5035 3335);
PAINT ORANGE (-5035 3335);
FORCEPROP 2 LASTPIN (-5025 3275) $PN DG38
J 2
(-5035 3285);
DISPLAY 0.617021 (-5035 3285);
PAINT ORANGE (-5035 3285);
FORCEPROP 2 LASTPIN (-5025 3225) $PN DE38
J 2
(-5035 3235);
DISPLAY 0.617021 (-5035 3235);
PAINT ORANGE (-5035 3235);
FORCEPROP 2 LASTPIN (-5025 3175) $PN DG42
J 2
(-5035 3185);
DISPLAY 0.617021 (-5035 3185);
PAINT ORANGE (-5035 3185);
FORCEPROP 2 LASTPIN (-5025 3125) $PN DD41
J 2
(-5035 3135);
DISPLAY 0.617021 (-5035 3135);
PAINT ORANGE (-5035 3135);
FORCEPROP 2 LASTPIN (-5025 3075) $PN CU64
J 2
(-5035 3085);
DISPLAY 0.617021 (-5035 3085);
PAINT ORANGE (-5035 3085);
FORCEPROP 2 LASTPIN (-5025 3025) $PN CN64
J 2
(-5035 3035);
DISPLAY 0.617021 (-5035 3035);
PAINT ORANGE (-5035 3035);
FORCEPROP 2 LASTPIN (-5025 2975) $PN CT67
J 2
(-5035 2985);
DISPLAY 0.617021 (-5035 2985);
PAINT ORANGE (-5035 2985);
FORCEPROP 2 LASTPIN (-5025 2925) $PN CP67
J 2
(-5035 2935);
DISPLAY 0.617021 (-5035 2935);
PAINT ORANGE (-5035 2935);
FORCEPROP 2 LASTPIN (-5025 2875) $PN CT63
J 2
(-5035 2885);
DISPLAY 0.617021 (-5035 2885);
PAINT ORANGE (-5035 2885);
FORCEPROP 2 LASTPIN (-5025 2825) $PN CP63
J 2
(-5035 2835);
DISPLAY 0.617021 (-5035 2835);
PAINT ORANGE (-5035 2835);
FORCEPROP 2 LASTPIN (-5025 2775) $PN CU66
J 2
(-5035 2785);
DISPLAY 0.617021 (-5035 2785);
PAINT ORANGE (-5035 2785);
FORCEPROP 2 LASTPIN (-5025 2725) $PN CN66
J 2
(-5035 2735);
DISPLAY 0.617021 (-5035 2735);
PAINT ORANGE (-5035 2735);
FORCEPROP 2 LASTPIN (-5025 2675) $PN DM71
J 2
(-5035 2685);
DISPLAY 0.617021 (-5035 2685);
PAINT ORANGE (-5035 2685);
FORCEPROP 2 LASTPIN (-5025 2625) $PN DK69
J 2
(-5035 2635);
DISPLAY 0.617021 (-5035 2635);
PAINT ORANGE (-5035 2635);
FORCEPROP 2 LASTPIN (-5025 2575) $PN DG72
J 2
(-5035 2585);
DISPLAY 0.617021 (-5035 2585);
PAINT ORANGE (-5035 2585);
FORCEPROP 2 LASTPIN (-5025 2525) $PN DF71
J 2
(-5035 2535);
DISPLAY 0.617021 (-5035 2535);
PAINT ORANGE (-5035 2535);
FORCEPROP 2 LASTPIN (-5025 2475) $PN DN70
J 2
(-5035 2485);
DISPLAY 0.617021 (-5035 2485);
PAINT ORANGE (-5035 2485);
FORCEPROP 2 LASTPIN (-5025 2425) $PN DM69
J 2
(-5035 2435);
DISPLAY 0.617021 (-5035 2435);
PAINT ORANGE (-5035 2435);
FORCEPROP 2 LASTPIN (-5025 2375) $PN DJ72
J 2
(-5035 2385);
DISPLAY 0.617021 (-5035 2385);
PAINT ORANGE (-5035 2385);
FORCEPROP 2 LASTPIN (-5025 2325) $PN DG70
J 2
(-5035 2335);
DISPLAY 0.617021 (-5035 2335);
PAINT ORANGE (-5035 2335);
FORCEPROP 2 LASTPIN (-5025 2275) $PN DH77
J 2
(-5035 2285);
DISPLAY 0.617021 (-5035 2285);
PAINT ORANGE (-5035 2285);
FORCEPROP 2 LASTPIN (-5025 2225) $PN DF77
J 2
(-5035 2235);
DISPLAY 0.617021 (-5035 2235);
PAINT ORANGE (-5035 2235);
FORCEPROP 2 LASTPIN (-5025 2175) $PN DB75
J 2
(-5035 2185);
DISPLAY 0.617021 (-5035 2185);
PAINT ORANGE (-5035 2185);
FORCEPROP 2 LASTPIN (-5025 2125) $PN DC74
J 2
(-5035 2135);
DISPLAY 0.617021 (-5035 2135);
PAINT ORANGE (-5035 2135);
FORCEPROP 2 LASTPIN (-5025 2075) $PN DJ76
J 2
(-5035 2085);
DISPLAY 0.617021 (-5035 2085);
PAINT ORANGE (-5035 2085);
FORCEPROP 2 LASTPIN (-5025 2025) $PN DH75
J 2
(-5035 2035);
DISPLAY 0.617021 (-5035 2035);
PAINT ORANGE (-5035 2035);
FORCEPROP 2 LASTPIN (-5025 1975) $PN DC76
J 2
(-5035 1985);
DISPLAY 0.617021 (-5035 1985);
PAINT ORANGE (-5035 1985);
FORCEPROP 2 LASTPIN (-5025 1925) $PN DE74
J 2
(-5035 1935);
DISPLAY 0.617021 (-5035 1935);
PAINT ORANGE (-5035 1935);
FORCEPROP 2 LASTPIN (-5025 1875) $PN CT77
J 2
(-5035 1885);
DISPLAY 0.617021 (-5035 1885);
PAINT ORANGE (-5035 1885);
FORCEPROP 2 LASTPIN (-5025 1825) $PN CV75
J 2
(-5035 1835);
DISPLAY 0.617021 (-5035 1835);
PAINT ORANGE (-5035 1835);
FORCEPROP 2 LASTPIN (-5025 1775) $PN CM75
J 2
(-5035 1785);
DISPLAY 0.617021 (-5035 1785);
PAINT ORANGE (-5035 1785);
FORCEPROP 2 LASTPIN (-5025 1725) $PN CN74
J 2
(-5035 1735);
DISPLAY 0.617021 (-5035 1735);
PAINT ORANGE (-5035 1735);
FORCEPROP 2 LASTPIN (-5025 1675) $PN CV77
J 2
(-5035 1685);
DISPLAY 0.617021 (-5035 1685);
PAINT ORANGE (-5035 1685);
FORCEPROP 2 LASTPIN (-5025 1625) $PN CW76
J 2
(-5035 1635);
DISPLAY 0.617021 (-5035 1635);
PAINT ORANGE (-5035 1635);
FORCEPROP 2 LASTPIN (-5025 1575) $PN CN76
J 2
(-5035 1585);
DISPLAY 0.617021 (-5035 1585);
PAINT ORANGE (-5035 1585);
FORCEPROP 2 LASTPIN (-5025 1525) $PN CR74
J 2
(-5035 1535);
DISPLAY 0.617021 (-5035 1535);
PAINT ORANGE (-5035 1535);
FORCEPROP 2 LASTPIN (-3325 1325) $PN DK45
J 0
(-3315 1335);
DISPLAY 0.617021 (-3315 1335);
PAINT ORANGE (-3315 1335);
FORCEPROP 2 LASTPIN (-3325 1275) $PN DM45
J 0
(-3315 1285);
DISPLAY 0.617021 (-3315 1285);
PAINT ORANGE (-3315 1285);
FORCEPROP 2 LASTPIN (-3325 1225) $PN DJ48
J 0
(-3315 1235);
DISPLAY 0.617021 (-3315 1235);
PAINT ORANGE (-3315 1235);
FORCEPROP 2 LASTPIN (-3325 1175) $PN DF51
J 0
(-3315 1185);
DISPLAY 0.617021 (-3315 1185);
PAINT ORANGE (-3315 1185);
FORCEPROP 2 LASTPIN (-3325 1125) $PN DG46
J 0
(-3315 1135);
DISPLAY 0.617021 (-3315 1135);
PAINT ORANGE (-3315 1135);
FORCEPROP 2 LASTPIN (-3325 1075) $PN DJ46
J 0
(-3315 1085);
DISPLAY 0.617021 (-3315 1085);
PAINT ORANGE (-3315 1085);
FORCEPROP 2 LASTPIN (-3325 1025) $PN DF49
J 0
(-3315 1035);
DISPLAY 0.617021 (-3315 1035);
PAINT ORANGE (-3315 1035);
FORCEPROP 2 LASTPIN (-3325 975) $PN DK51
J 0
(-3315 985);
DISPLAY 0.617021 (-3315 985);
PAINT ORANGE (-3315 985);
FORCEPROP 2 LASTPIN (-5025 975) $PN DG56
J 2
(-5035 985);
DISPLAY 0.617021 (-5035 985);
PAINT ORANGE (-5035 985);
FORCEPROP 2 LASTPIN (-5025 925) $PN DJ56
J 2
(-5035 935);
DISPLAY 0.617021 (-5035 935);
PAINT ORANGE (-5035 935);
FORCEPROP 2 LASTPIN (-5025 875) $PN DG54
J 2
(-5035 885);
DISPLAY 0.617021 (-5035 885);
PAINT ORANGE (-5035 885);
FORCEPROP 2 LASTPIN (-5025 825) $PN DJ54
J 2
(-5035 835);
DISPLAY 0.617021 (-5035 835);
PAINT ORANGE (-5035 835);
FORCEPROP 2 LASTPIN (-5025 775) $PN DF57
J 2
(-5035 785);
DISPLAY 0.617021 (-5035 785);
PAINT ORANGE (-5035 785);
FORCEPROP 2 LASTPIN (-5025 725) $PN DK57
J 2
(-5035 735);
DISPLAY 0.617021 (-5035 735);
PAINT ORANGE (-5035 735);
FORCEPROP 2 LASTPIN (-5025 675) $PN DF55
J 2
(-5035 685);
DISPLAY 0.617021 (-5035 685);
PAINT ORANGE (-5035 685);
FORCEPROP 2 LASTPIN (-5025 625) $PN DK55
J 2
(-5035 635);
DISPLAY 0.617021 (-5035 635);
PAINT ORANGE (-5035 635);
FORCEPROP 2 LASTPIN (-3325 1825) $PN DF63
J 0
(-3315 1835);
DISPLAY 0.617021 (-3315 1835);
PAINT ORANGE (-3315 1835);
FORCEPROP 2 LASTPIN (-3325 1775) $PN DK63
J 0
(-3315 1785);
DISPLAY 0.617021 (-3315 1785);
PAINT ORANGE (-3315 1785);
FORCEPROP 2 LASTPIN (-3325 1725) $PN DD63
J 0
(-3315 1735);
DISPLAY 0.617021 (-3315 1735);
PAINT ORANGE (-3315 1735);
FORCEPROP 2 LASTPIN (-3325 1675) $PN DG62
J 0
(-3315 1685);
DISPLAY 0.617021 (-3315 1685);
PAINT ORANGE (-3315 1685);
FORCEPROP 2 LASTPIN (-5025 525) $PN DF45
J 2
(-5035 535);
DISPLAY 0.617021 (-5035 535);
PAINT ORANGE (-5035 535);
FORCEPROP 2 LASTPIN (-3325 875) $PN DF61
J 0
(-3315 885);
DISPLAY 0.617021 (-3315 885);
PAINT ORANGE (-3315 885);
FORCEPROP 2 LASTPIN (-3325 825) $PN DA62
J 0
(-3315 835);
DISPLAY 0.617021 (-3315 835);
PAINT ORANGE (-3315 835);
FORCEPROP 2 LASTPIN (-3325 775) $PN DC56
J 0
(-3315 785);
DISPLAY 0.617021 (-3315 785);
PAINT ORANGE (-3315 785);
FORCEPROP 2 LASTPIN (-3325 725) $PN DJ52
J 0
(-3315 735);
DISPLAY 0.617021 (-3315 735);
PAINT ORANGE (-3315 735);
FORCEPROP 2 LASTPIN (-3325 575) $PN DD61
J 0
(-3315 585);
DISPLAY 0.617021 (-3315 585);
PAINT ORANGE (-3315 585);
FORCEPROP 2 LASTPIN (-3325 625) $PN DC62
J 0
(-3315 635);
DISPLAY 0.617021 (-3315 635);
PAINT ORANGE (-3315 635);
FORCEPROP 1 LAST PACK_TYPE BGA1
J 0
(-4975 4975);
PAINT SKYBLUE (-4975 4975);
DISPLAY INVISIBLE (-4975 4975);
FORCEPROP 2 LAST CDS_LIB chpset_lib
J 0
(-4175 2575);
PAINT ORANGE (-4175 2575);
DISPLAY INVISIBLE (-4175 2575);
FORCEPROP 2 LAST SEC_TYPE BGA1
J 0
(-4975 4975);
DISPLAY 1.021277 (-4975 4975);
PAINT ORANGE (-4975 4975);
DISPLAY INVISIBLE (-4975 4975);
FORCEPROP 2 LAST SEC 8
J 0
(-4975 4975);
DISPLAY 0.680851 (-4975 4975);
PAINT MONO (-4975 4975);
DISPLAY INVISIBLE (-4975 4975);
FORCEPROP 2 LAST CDS_LOCATION U5D1
J 0
(-4975 4925);
DISPLAY 0.617021 (-4975 4925);
PAINT AQUA (-4975 4925);
DISPLAY INVISIBLE (-4975 4925);
FORCEPROP 1 LAST PATH I172
J 0
(-4175 4875);
PAINT GREEN (-4175 4875);
DISPLAY INVISIBLE (-4175 4875);
FORCEPROP 0 LAST ROOM CPU0
J 0
(-4975 5025);
DISPLAY 1.021277 (-4975 5025);
PAINT ORANGE (-4975 5025);
DISPLAY INVISIBLE (-4975 5025);
FORCEADD TAP..6
(-5575 1325);
FORCEPROP 3 LASTPIN (-5525 1325) SIG_NAME M_F_ECC<5>
J 0
(-5515 1335);
DISPLAY 0.659574 (-5515 1335);
PAINT MONO (-5515 1335);
DISPLAY INVISIBLE (-5515 1335);
FORCEPROP 1 LASTPIN (-5525 1325) BN 5
J 0
(-5577 1333);
DISPLAY 0.617021 (-5577 1333);
PAINT PINK (-5577 1333);
FORCEPROP 2 LAST CDS_LIB mstr_standard
J 0
(-5575 1325);
PAINT MONO (-5575 1325);
DISPLAY INVISIBLE (-5575 1325);
FORCEPROP 1 LAST BODY_TYPE PLUMBING
J 0
(-5575 1275);
DISPLAY 1.595745 (-5575 1275);
PAINT GREEN (-5575 1275);
DISPLAY INVISIBLE (-5575 1275);
FORCEPROP 1 LAST HDL_TAP TRUE
J 0
(-5250 1200);
DISPLAY 1.595745 (-5250 1200);
PAINT GREEN (-5250 1200);
DISPLAY INVISIBLE (-5250 1200);
FORCEPROP 1 LAST PATH I18
J 0
(-5577 1325);
DISPLAY 0.872340 (-5577 1325);
PAINT GREEN (-5577 1325);
DISPLAY INVISIBLE (-5577 1325);
FORCEADD TAP..6
(-5575 1375);
FORCEPROP 3 LASTPIN (-5525 1375) SIG_NAME M_F_ECC<6>
J 0
(-5515 1385);
DISPLAY 0.659574 (-5515 1385);
PAINT MONO (-5515 1385);
DISPLAY INVISIBLE (-5515 1385);
FORCEPROP 1 LASTPIN (-5525 1375) BN 6
J 0
(-5577 1383);
DISPLAY 0.617021 (-5577 1383);
PAINT PINK (-5577 1383);
FORCEPROP 2 LAST CDS_LIB mstr_standard
J 0
(-5575 1375);
PAINT MONO (-5575 1375);
DISPLAY INVISIBLE (-5575 1375);
FORCEPROP 1 LAST BODY_TYPE PLUMBING
J 0
(-5575 1325);
DISPLAY 1.595745 (-5575 1325);
PAINT GREEN (-5575 1325);
DISPLAY INVISIBLE (-5575 1325);
FORCEPROP 1 LAST HDL_TAP TRUE
J 0
(-5250 1250);
DISPLAY 1.595745 (-5250 1250);
PAINT GREEN (-5250 1250);
DISPLAY INVISIBLE (-5250 1250);
FORCEPROP 1 LAST PATH I19
J 0
(-5577 1375);
DISPLAY 0.872340 (-5577 1375);
PAINT GREEN (-5577 1375);
DISPLAY INVISIBLE (-5577 1375);
FORCEADD OFFPAGE..5
(-6425 825);
FORCEPROP 2 LAST $XR0 53 
J 0
(-6679 825);
DISPLAY 0.638298 (-6679 825);
PAINT MONO (-6679 825);
FORCEPROP 2 LAST $XR1 54 
J 0
(-6769 825);
DISPLAY 0.638298 (-6769 825);
PAINT MONO (-6769 825);
FORCEPROP 2 LAST CDS_LIB mstr_standard
J 0
(-6425 825);
PAINT MONO (-6425 825);
DISPLAY INVISIBLE (-6425 825);
FORCEPROP 1 LAST OFFPAGE TRUE
J 0
(-6100 700);
DISPLAY 1.170213 (-6100 700);
PAINT GREEN (-6100 700);
DISPLAY INVISIBLE (-6100 700);
FORCEPROP 1 LAST COMMENT_BODY TRUE
J 0
(-6325 750);
DISPLAY 1.170213 (-6325 750);
PAINT GREEN (-6325 750);
DISPLAY INVISIBLE (-6325 750);
FORCEPROP 2 LAST PATH I2
J 0
(-6375 900);
DISPLAY 1.021277 (-6375 900);
PAINT ORANGE (-6375 900);
DISPLAY INVISIBLE (-6375 900);
FORCEADD TAP..6
(-5575 1425);
FORCEPROP 3 LASTPIN (-5525 1425) SIG_NAME M_F_ECC<7>
J 0
(-5515 1435);
DISPLAY 0.659574 (-5515 1435);
PAINT MONO (-5515 1435);
DISPLAY INVISIBLE (-5515 1435);
FORCEPROP 1 LASTPIN (-5525 1425) BN 7
J 0
(-5577 1433);
DISPLAY 0.617021 (-5577 1433);
PAINT PINK (-5577 1433);
FORCEPROP 2 LAST CDS_LIB mstr_standard
J 0
(-5575 1425);
PAINT MONO (-5575 1425);
DISPLAY INVISIBLE (-5575 1425);
FORCEPROP 1 LAST BODY_TYPE PLUMBING
J 0
(-5575 1375);
DISPLAY 1.595745 (-5575 1375);
PAINT GREEN (-5575 1375);
DISPLAY INVISIBLE (-5575 1375);
FORCEPROP 1 LAST HDL_TAP TRUE
J 0
(-5250 1300);
DISPLAY 1.595745 (-5250 1300);
PAINT GREEN (-5250 1300);
DISPLAY INVISIBLE (-5250 1300);
FORCEPROP 1 LAST PATH I20
J 0
(-5577 1425);
DISPLAY 0.872340 (-5577 1425);
PAINT GREEN (-5577 1425);
DISPLAY INVISIBLE (-5577 1425);
FORCEADD TAP..6
(-5575 1575);
FORCEPROP 3 LASTPIN (-5525 1575) SIG_NAME M_F_DQ<1>
J 0
(-5515 1585);
DISPLAY 0.659574 (-5515 1585);
PAINT MONO (-5515 1585);
DISPLAY INVISIBLE (-5515 1585);
FORCEPROP 1 LASTPIN (-5525 1575) BN 1
J 0
(-5577 1583);
DISPLAY 0.617021 (-5577 1583);
PAINT PINK (-5577 1583);
FORCEPROP 2 LAST CDS_LIB mstr_standard
J 0
(-5575 1575);
PAINT MONO (-5575 1575);
DISPLAY INVISIBLE (-5575 1575);
FORCEPROP 1 LAST BODY_TYPE PLUMBING
J 0
(-5575 1525);
DISPLAY 1.595745 (-5575 1525);
PAINT GREEN (-5575 1525);
DISPLAY INVISIBLE (-5575 1525);
FORCEPROP 1 LAST HDL_TAP TRUE
J 0
(-5250 1450);
DISPLAY 1.595745 (-5250 1450);
PAINT GREEN (-5250 1450);
DISPLAY INVISIBLE (-5250 1450);
FORCEPROP 1 LAST PATH I21
J 0
(-5577 1575);
DISPLAY 0.872340 (-5577 1575);
PAINT GREEN (-5577 1575);
DISPLAY INVISIBLE (-5577 1575);
FORCEADD TAP..6
(-5575 1525);
FORCEPROP 3 LASTPIN (-5525 1525) SIG_NAME M_F_DQ<0>
J 0
(-5515 1535);
DISPLAY 0.659574 (-5515 1535);
PAINT MONO (-5515 1535);
DISPLAY INVISIBLE (-5515 1535);
FORCEPROP 1 LASTPIN (-5525 1525) BN 0
J 0
(-5577 1533);
DISPLAY 0.617021 (-5577 1533);
PAINT PINK (-5577 1533);
FORCEPROP 2 LAST CDS_LIB mstr_standard
J 0
(-5575 1525);
PAINT MONO (-5575 1525);
DISPLAY INVISIBLE (-5575 1525);
FORCEPROP 1 LAST BODY_TYPE PLUMBING
J 0
(-5575 1475);
DISPLAY 1.595745 (-5575 1475);
PAINT GREEN (-5575 1475);
DISPLAY INVISIBLE (-5575 1475);
FORCEPROP 1 LAST HDL_TAP TRUE
J 0
(-5250 1400);
DISPLAY 1.595745 (-5250 1400);
PAINT GREEN (-5250 1400);
DISPLAY INVISIBLE (-5250 1400);
FORCEPROP 1 LAST PATH I22
J 0
(-5577 1525);
DISPLAY 0.872340 (-5577 1525);
PAINT GREEN (-5577 1525);
DISPLAY INVISIBLE (-5577 1525);
FORCEADD TAP..6
(-5575 1625);
FORCEPROP 3 LASTPIN (-5525 1625) SIG_NAME M_F_DQ<2>
J 0
(-5515 1635);
DISPLAY 0.659574 (-5515 1635);
PAINT MONO (-5515 1635);
DISPLAY INVISIBLE (-5515 1635);
FORCEPROP 1 LASTPIN (-5525 1625) BN 2
J 0
(-5577 1633);
DISPLAY 0.617021 (-5577 1633);
PAINT PINK (-5577 1633);
FORCEPROP 2 LAST CDS_LIB mstr_standard
J 0
(-5575 1625);
PAINT MONO (-5575 1625);
DISPLAY INVISIBLE (-5575 1625);
FORCEPROP 1 LAST BODY_TYPE PLUMBING
J 0
(-5575 1575);
DISPLAY 1.595745 (-5575 1575);
PAINT GREEN (-5575 1575);
DISPLAY INVISIBLE (-5575 1575);
FORCEPROP 1 LAST HDL_TAP TRUE
J 0
(-5250 1500);
DISPLAY 1.595745 (-5250 1500);
PAINT GREEN (-5250 1500);
DISPLAY INVISIBLE (-5250 1500);
FORCEPROP 1 LAST PATH I23
J 0
(-5577 1625);
DISPLAY 0.872340 (-5577 1625);
PAINT GREEN (-5577 1625);
DISPLAY INVISIBLE (-5577 1625);
FORCEADD TAP..6
(-5575 1675);
FORCEPROP 3 LASTPIN (-5525 1675) SIG_NAME M_F_DQ<3>
J 0
(-5515 1685);
DISPLAY 0.659574 (-5515 1685);
PAINT MONO (-5515 1685);
DISPLAY INVISIBLE (-5515 1685);
FORCEPROP 1 LASTPIN (-5525 1675) BN 3
J 0
(-5577 1683);
DISPLAY 0.617021 (-5577 1683);
PAINT PINK (-5577 1683);
FORCEPROP 2 LAST CDS_LIB mstr_standard
J 0
(-5575 1675);
PAINT MONO (-5575 1675);
DISPLAY INVISIBLE (-5575 1675);
FORCEPROP 1 LAST BODY_TYPE PLUMBING
J 0
(-5575 1625);
DISPLAY 1.595745 (-5575 1625);
PAINT GREEN (-5575 1625);
DISPLAY INVISIBLE (-5575 1625);
FORCEPROP 1 LAST HDL_TAP TRUE
J 0
(-5250 1550);
DISPLAY 1.595745 (-5250 1550);
PAINT GREEN (-5250 1550);
DISPLAY INVISIBLE (-5250 1550);
FORCEPROP 1 LAST PATH I24
J 0
(-5577 1675);
DISPLAY 0.872340 (-5577 1675);
PAINT GREEN (-5577 1675);
DISPLAY INVISIBLE (-5577 1675);
FORCEADD TAP..6
(-5575 1725);
FORCEPROP 3 LASTPIN (-5525 1725) SIG_NAME M_F_DQ<4>
J 0
(-5515 1735);
DISPLAY 0.659574 (-5515 1735);
PAINT MONO (-5515 1735);
DISPLAY INVISIBLE (-5515 1735);
FORCEPROP 1 LASTPIN (-5525 1725) BN 4
J 0
(-5577 1733);
DISPLAY 0.617021 (-5577 1733);
PAINT PINK (-5577 1733);
FORCEPROP 2 LAST CDS_LIB mstr_standard
J 0
(-5575 1725);
PAINT MONO (-5575 1725);
DISPLAY INVISIBLE (-5575 1725);
FORCEPROP 1 LAST BODY_TYPE PLUMBING
J 0
(-5575 1675);
DISPLAY 1.595745 (-5575 1675);
PAINT GREEN (-5575 1675);
DISPLAY INVISIBLE (-5575 1675);
FORCEPROP 1 LAST HDL_TAP TRUE
J 0
(-5250 1600);
DISPLAY 1.595745 (-5250 1600);
PAINT GREEN (-5250 1600);
DISPLAY INVISIBLE (-5250 1600);
FORCEPROP 1 LAST PATH I25
J 0
(-5577 1725);
DISPLAY 0.872340 (-5577 1725);
PAINT GREEN (-5577 1725);
DISPLAY INVISIBLE (-5577 1725);
FORCEADD TAP..6
(-5575 1775);
FORCEPROP 3 LASTPIN (-5525 1775) SIG_NAME M_F_DQ<5>
J 0
(-5515 1785);
DISPLAY 0.659574 (-5515 1785);
PAINT MONO (-5515 1785);
DISPLAY INVISIBLE (-5515 1785);
FORCEPROP 1 LASTPIN (-5525 1775) BN 5
J 0
(-5577 1783);
DISPLAY 0.617021 (-5577 1783);
PAINT PINK (-5577 1783);
FORCEPROP 2 LAST CDS_LIB mstr_standard
J 0
(-5575 1775);
PAINT MONO (-5575 1775);
DISPLAY INVISIBLE (-5575 1775);
FORCEPROP 1 LAST BODY_TYPE PLUMBING
J 0
(-5575 1725);
DISPLAY 1.595745 (-5575 1725);
PAINT GREEN (-5575 1725);
DISPLAY INVISIBLE (-5575 1725);
FORCEPROP 1 LAST HDL_TAP TRUE
J 0
(-5250 1650);
DISPLAY 1.595745 (-5250 1650);
PAINT GREEN (-5250 1650);
DISPLAY INVISIBLE (-5250 1650);
FORCEPROP 1 LAST PATH I26
J 0
(-5577 1775);
DISPLAY 0.872340 (-5577 1775);
PAINT GREEN (-5577 1775);
DISPLAY INVISIBLE (-5577 1775);
FORCEADD TAP..6
(-5575 1825);
FORCEPROP 3 LASTPIN (-5525 1825) SIG_NAME M_F_DQ<6>
J 0
(-5515 1835);
DISPLAY 0.659574 (-5515 1835);
PAINT MONO (-5515 1835);
DISPLAY INVISIBLE (-5515 1835);
FORCEPROP 1 LASTPIN (-5525 1825) BN 6
J 0
(-5577 1833);
DISPLAY 0.617021 (-5577 1833);
PAINT PINK (-5577 1833);
FORCEPROP 2 LAST CDS_LIB mstr_standard
J 0
(-5575 1825);
PAINT MONO (-5575 1825);
DISPLAY INVISIBLE (-5575 1825);
FORCEPROP 1 LAST BODY_TYPE PLUMBING
J 0
(-5575 1775);
DISPLAY 1.595745 (-5575 1775);
PAINT GREEN (-5575 1775);
DISPLAY INVISIBLE (-5575 1775);
FORCEPROP 1 LAST HDL_TAP TRUE
J 0
(-5250 1700);
DISPLAY 1.595745 (-5250 1700);
PAINT GREEN (-5250 1700);
DISPLAY INVISIBLE (-5250 1700);
FORCEPROP 1 LAST PATH I27
J 0
(-5577 1825);
DISPLAY 0.872340 (-5577 1825);
PAINT GREEN (-5577 1825);
DISPLAY INVISIBLE (-5577 1825);
FORCEADD TAP..6
(-5575 1925);
FORCEPROP 3 LASTPIN (-5525 1925) SIG_NAME M_F_DQ<8>
J 0
(-5515 1935);
DISPLAY 0.659574 (-5515 1935);
PAINT MONO (-5515 1935);
DISPLAY INVISIBLE (-5515 1935);
FORCEPROP 1 LASTPIN (-5525 1925) BN 8
J 0
(-5577 1933);
DISPLAY 0.617021 (-5577 1933);
PAINT PINK (-5577 1933);
FORCEPROP 2 LAST CDS_LIB mstr_standard
J 0
(-5575 1925);
PAINT MONO (-5575 1925);
DISPLAY INVISIBLE (-5575 1925);
FORCEPROP 1 LAST BODY_TYPE PLUMBING
J 0
(-5575 1875);
DISPLAY 1.595745 (-5575 1875);
PAINT GREEN (-5575 1875);
DISPLAY INVISIBLE (-5575 1875);
FORCEPROP 1 LAST HDL_TAP TRUE
J 0
(-5250 1800);
DISPLAY 1.595745 (-5250 1800);
PAINT GREEN (-5250 1800);
DISPLAY INVISIBLE (-5250 1800);
FORCEPROP 1 LAST PATH I28
J 0
(-5577 1925);
DISPLAY 0.872340 (-5577 1925);
PAINT GREEN (-5577 1925);
DISPLAY INVISIBLE (-5577 1925);
FORCEADD TAP..6
(-5575 1875);
FORCEPROP 3 LASTPIN (-5525 1875) SIG_NAME M_F_DQ<7>
J 0
(-5515 1885);
DISPLAY 0.659574 (-5515 1885);
PAINT MONO (-5515 1885);
DISPLAY INVISIBLE (-5515 1885);
FORCEPROP 1 LASTPIN (-5525 1875) BN 7
J 0
(-5577 1883);
DISPLAY 0.617021 (-5577 1883);
PAINT PINK (-5577 1883);
FORCEPROP 2 LAST CDS_LIB mstr_standard
J 0
(-5575 1875);
PAINT MONO (-5575 1875);
DISPLAY INVISIBLE (-5575 1875);
FORCEPROP 1 LAST BODY_TYPE PLUMBING
J 0
(-5575 1825);
DISPLAY 1.595745 (-5575 1825);
PAINT GREEN (-5575 1825);
DISPLAY INVISIBLE (-5575 1825);
FORCEPROP 1 LAST HDL_TAP TRUE
J 0
(-5250 1750);
DISPLAY 1.595745 (-5250 1750);
PAINT GREEN (-5250 1750);
DISPLAY INVISIBLE (-5250 1750);
FORCEPROP 1 LAST PATH I29
J 0
(-5577 1875);
DISPLAY 0.872340 (-5577 1875);
PAINT GREEN (-5577 1875);
DISPLAY INVISIBLE (-5577 1875);
FORCEADD OFFPAGE..5
(-6425 1025);
FORCEPROP 2 LAST $XR0 53 
J 0
(-6679 1025);
DISPLAY 0.638298 (-6679 1025);
PAINT MONO (-6679 1025);
FORCEPROP 2 LAST $XR1 54 
J 0
(-6769 1025);
DISPLAY 0.638298 (-6769 1025);
PAINT MONO (-6769 1025);
FORCEPROP 2 LAST CDS_LIB mstr_standard
J 0
(-6425 1025);
PAINT MONO (-6425 1025);
DISPLAY INVISIBLE (-6425 1025);
FORCEPROP 1 LAST OFFPAGE TRUE
J 0
(-6100 900);
DISPLAY 1.170213 (-6100 900);
PAINT GREEN (-6100 900);
DISPLAY INVISIBLE (-6100 900);
FORCEPROP 1 LAST COMMENT_BODY TRUE
J 0
(-6325 950);
DISPLAY 1.170213 (-6325 950);
PAINT GREEN (-6325 950);
DISPLAY INVISIBLE (-6325 950);
FORCEPROP 2 LAST PATH I3
J 0
(-6375 1100);
DISPLAY 1.021277 (-6375 1100);
PAINT ORANGE (-6375 1100);
DISPLAY INVISIBLE (-6375 1100);
FORCEADD TAP..6
(-5575 1975);
FORCEPROP 3 LASTPIN (-5525 1975) SIG_NAME M_F_DQ<9>
J 0
(-5515 1985);
DISPLAY 0.659574 (-5515 1985);
PAINT MONO (-5515 1985);
DISPLAY INVISIBLE (-5515 1985);
FORCEPROP 1 LASTPIN (-5525 1975) BN 9
J 0
(-5577 1983);
DISPLAY 0.617021 (-5577 1983);
PAINT PINK (-5577 1983);
FORCEPROP 2 LAST CDS_LIB mstr_standard
J 0
(-5575 1975);
PAINT MONO (-5575 1975);
DISPLAY INVISIBLE (-5575 1975);
FORCEPROP 1 LAST BODY_TYPE PLUMBING
J 0
(-5575 1925);
DISPLAY 1.595745 (-5575 1925);
PAINT GREEN (-5575 1925);
DISPLAY INVISIBLE (-5575 1925);
FORCEPROP 1 LAST HDL_TAP TRUE
J 0
(-5250 1850);
DISPLAY 1.595745 (-5250 1850);
PAINT GREEN (-5250 1850);
DISPLAY INVISIBLE (-5250 1850);
FORCEPROP 1 LAST PATH I30
J 0
(-5577 1975);
DISPLAY 0.872340 (-5577 1975);
PAINT GREEN (-5577 1975);
DISPLAY INVISIBLE (-5577 1975);
FORCEADD TAP..6
(-5575 2025);
FORCEPROP 3 LASTPIN (-5525 2025) SIG_NAME M_F_DQ<10>
J 0
(-5515 2035);
DISPLAY 0.659574 (-5515 2035);
PAINT MONO (-5515 2035);
DISPLAY INVISIBLE (-5515 2035);
FORCEPROP 1 LASTPIN (-5525 2025) BN 10
J 0
(-5577 2033);
DISPLAY 0.617021 (-5577 2033);
PAINT PINK (-5577 2033);
FORCEPROP 2 LAST CDS_LIB mstr_standard
J 0
(-5575 2025);
PAINT MONO (-5575 2025);
DISPLAY INVISIBLE (-5575 2025);
FORCEPROP 1 LAST BODY_TYPE PLUMBING
J 0
(-5575 1975);
DISPLAY 1.595745 (-5575 1975);
PAINT GREEN (-5575 1975);
DISPLAY INVISIBLE (-5575 1975);
FORCEPROP 1 LAST HDL_TAP TRUE
J 0
(-5250 1900);
DISPLAY 1.595745 (-5250 1900);
PAINT GREEN (-5250 1900);
DISPLAY INVISIBLE (-5250 1900);
FORCEPROP 1 LAST PATH I32
J 0
(-5577 2025);
DISPLAY 0.872340 (-5577 2025);
PAINT GREEN (-5577 2025);
DISPLAY INVISIBLE (-5577 2025);
FORCEADD TAP..6
(-5575 2075);
FORCEPROP 3 LASTPIN (-5525 2075) SIG_NAME M_F_DQ<11>
J 0
(-5515 2085);
DISPLAY 0.659574 (-5515 2085);
PAINT MONO (-5515 2085);
DISPLAY INVISIBLE (-5515 2085);
FORCEPROP 1 LASTPIN (-5525 2075) BN 11
J 0
(-5577 2083);
DISPLAY 0.617021 (-5577 2083);
PAINT PINK (-5577 2083);
FORCEPROP 2 LAST CDS_LIB mstr_standard
J 0
(-5575 2075);
PAINT MONO (-5575 2075);
DISPLAY INVISIBLE (-5575 2075);
FORCEPROP 1 LAST BODY_TYPE PLUMBING
J 0
(-5575 2025);
DISPLAY 1.595745 (-5575 2025);
PAINT GREEN (-5575 2025);
DISPLAY INVISIBLE (-5575 2025);
FORCEPROP 1 LAST HDL_TAP TRUE
J 0
(-5250 1950);
DISPLAY 1.595745 (-5250 1950);
PAINT GREEN (-5250 1950);
DISPLAY INVISIBLE (-5250 1950);
FORCEPROP 1 LAST PATH I33
J 0
(-5577 2075);
DISPLAY 0.872340 (-5577 2075);
PAINT GREEN (-5577 2075);
DISPLAY INVISIBLE (-5577 2075);
FORCEADD TAP..6
(-5575 2125);
FORCEPROP 3 LASTPIN (-5525 2125) SIG_NAME M_F_DQ<12>
J 0
(-5515 2135);
DISPLAY 0.659574 (-5515 2135);
PAINT MONO (-5515 2135);
DISPLAY INVISIBLE (-5515 2135);
FORCEPROP 1 LASTPIN (-5525 2125) BN 12
J 0
(-5577 2133);
DISPLAY 0.617021 (-5577 2133);
PAINT PINK (-5577 2133);
FORCEPROP 2 LAST CDS_LIB mstr_standard
J 0
(-5575 2125);
PAINT MONO (-5575 2125);
DISPLAY INVISIBLE (-5575 2125);
FORCEPROP 1 LAST BODY_TYPE PLUMBING
J 0
(-5575 2075);
DISPLAY 1.595745 (-5575 2075);
PAINT GREEN (-5575 2075);
DISPLAY INVISIBLE (-5575 2075);
FORCEPROP 1 LAST HDL_TAP TRUE
J 0
(-5250 2000);
DISPLAY 1.595745 (-5250 2000);
PAINT GREEN (-5250 2000);
DISPLAY INVISIBLE (-5250 2000);
FORCEPROP 1 LAST PATH I34
J 0
(-5577 2125);
DISPLAY 0.872340 (-5577 2125);
PAINT GREEN (-5577 2125);
DISPLAY INVISIBLE (-5577 2125);
FORCEADD TAP..6
(-5575 2175);
FORCEPROP 3 LASTPIN (-5525 2175) SIG_NAME M_F_DQ<13>
J 0
(-5515 2185);
DISPLAY 0.659574 (-5515 2185);
PAINT MONO (-5515 2185);
DISPLAY INVISIBLE (-5515 2185);
FORCEPROP 1 LASTPIN (-5525 2175) BN 13
J 0
(-5577 2183);
DISPLAY 0.617021 (-5577 2183);
PAINT PINK (-5577 2183);
FORCEPROP 2 LAST CDS_LIB mstr_standard
J 0
(-5575 2175);
PAINT MONO (-5575 2175);
DISPLAY INVISIBLE (-5575 2175);
FORCEPROP 1 LAST BODY_TYPE PLUMBING
J 0
(-5575 2125);
DISPLAY 1.595745 (-5575 2125);
PAINT GREEN (-5575 2125);
DISPLAY INVISIBLE (-5575 2125);
FORCEPROP 1 LAST HDL_TAP TRUE
J 0
(-5250 2050);
DISPLAY 1.595745 (-5250 2050);
PAINT GREEN (-5250 2050);
DISPLAY INVISIBLE (-5250 2050);
FORCEPROP 1 LAST PATH I35
J 0
(-5577 2175);
DISPLAY 0.872340 (-5577 2175);
PAINT GREEN (-5577 2175);
DISPLAY INVISIBLE (-5577 2175);
FORCEADD TAP..6
(-5575 2225);
FORCEPROP 3 LASTPIN (-5525 2225) SIG_NAME M_F_DQ<14>
J 0
(-5515 2235);
DISPLAY 0.659574 (-5515 2235);
PAINT MONO (-5515 2235);
DISPLAY INVISIBLE (-5515 2235);
FORCEPROP 1 LASTPIN (-5525 2225) BN 14
J 0
(-5577 2233);
DISPLAY 0.617021 (-5577 2233);
PAINT PINK (-5577 2233);
FORCEPROP 2 LAST CDS_LIB mstr_standard
J 0
(-5575 2225);
PAINT MONO (-5575 2225);
DISPLAY INVISIBLE (-5575 2225);
FORCEPROP 1 LAST BODY_TYPE PLUMBING
J 0
(-5575 2175);
DISPLAY 1.595745 (-5575 2175);
PAINT GREEN (-5575 2175);
DISPLAY INVISIBLE (-5575 2175);
FORCEPROP 1 LAST HDL_TAP TRUE
J 0
(-5250 2100);
DISPLAY 1.595745 (-5250 2100);
PAINT GREEN (-5250 2100);
DISPLAY INVISIBLE (-5250 2100);
FORCEPROP 1 LAST PATH I36
J 0
(-5577 2225);
DISPLAY 0.872340 (-5577 2225);
PAINT GREEN (-5577 2225);
DISPLAY INVISIBLE (-5577 2225);
FORCEADD TAP..6
(-5575 2275);
FORCEPROP 3 LASTPIN (-5525 2275) SIG_NAME M_F_DQ<15>
J 0
(-5515 2285);
DISPLAY 0.659574 (-5515 2285);
PAINT MONO (-5515 2285);
DISPLAY INVISIBLE (-5515 2285);
FORCEPROP 1 LASTPIN (-5525 2275) BN 15
J 0
(-5577 2283);
DISPLAY 0.617021 (-5577 2283);
PAINT PINK (-5577 2283);
FORCEPROP 2 LAST CDS_LIB mstr_standard
J 0
(-5575 2275);
PAINT MONO (-5575 2275);
DISPLAY INVISIBLE (-5575 2275);
FORCEPROP 1 LAST BODY_TYPE PLUMBING
J 0
(-5575 2225);
DISPLAY 1.595745 (-5575 2225);
PAINT GREEN (-5575 2225);
DISPLAY INVISIBLE (-5575 2225);
FORCEPROP 1 LAST HDL_TAP TRUE
J 0
(-5250 2150);
DISPLAY 1.595745 (-5250 2150);
PAINT GREEN (-5250 2150);
DISPLAY INVISIBLE (-5250 2150);
FORCEPROP 1 LAST PATH I37
J 0
(-5577 2275);
DISPLAY 0.872340 (-5577 2275);
PAINT GREEN (-5577 2275);
DISPLAY INVISIBLE (-5577 2275);
FORCEADD TAP..6
(-5575 2325);
FORCEPROP 3 LASTPIN (-5525 2325) SIG_NAME M_F_DQ<16>
J 0
(-5515 2335);
DISPLAY 0.659574 (-5515 2335);
PAINT MONO (-5515 2335);
DISPLAY INVISIBLE (-5515 2335);
FORCEPROP 1 LASTPIN (-5525 2325) BN 16
J 0
(-5577 2333);
DISPLAY 0.617021 (-5577 2333);
PAINT PINK (-5577 2333);
FORCEPROP 2 LAST CDS_LIB mstr_standard
J 0
(-5575 2325);
PAINT MONO (-5575 2325);
DISPLAY INVISIBLE (-5575 2325);
FORCEPROP 1 LAST BODY_TYPE PLUMBING
J 0
(-5575 2275);
DISPLAY 1.595745 (-5575 2275);
PAINT GREEN (-5575 2275);
DISPLAY INVISIBLE (-5575 2275);
FORCEPROP 1 LAST HDL_TAP TRUE
J 0
(-5250 2200);
DISPLAY 1.595745 (-5250 2200);
PAINT GREEN (-5250 2200);
DISPLAY INVISIBLE (-5250 2200);
FORCEPROP 1 LAST PATH I38
J 0
(-5577 2325);
DISPLAY 0.872340 (-5577 2325);
PAINT GREEN (-5577 2325);
DISPLAY INVISIBLE (-5577 2325);
FORCEADD TAP..6
(-5575 2375);
FORCEPROP 3 LASTPIN (-5525 2375) SIG_NAME M_F_DQ<17>
J 0
(-5515 2385);
DISPLAY 0.659574 (-5515 2385);
PAINT MONO (-5515 2385);
DISPLAY INVISIBLE (-5515 2385);
FORCEPROP 1 LASTPIN (-5525 2375) BN 17
J 0
(-5577 2383);
DISPLAY 0.617021 (-5577 2383);
PAINT PINK (-5577 2383);
FORCEPROP 2 LAST CDS_LIB mstr_standard
J 0
(-5575 2375);
PAINT MONO (-5575 2375);
DISPLAY INVISIBLE (-5575 2375);
FORCEPROP 1 LAST BODY_TYPE PLUMBING
J 0
(-5575 2325);
DISPLAY 1.595745 (-5575 2325);
PAINT GREEN (-5575 2325);
DISPLAY INVISIBLE (-5575 2325);
FORCEPROP 1 LAST HDL_TAP TRUE
J 0
(-5250 2250);
DISPLAY 1.595745 (-5250 2250);
PAINT GREEN (-5250 2250);
DISPLAY INVISIBLE (-5250 2250);
FORCEPROP 1 LAST PATH I39
J 0
(-5577 2375);
DISPLAY 0.872340 (-5577 2375);
PAINT GREEN (-5577 2375);
DISPLAY INVISIBLE (-5577 2375);
FORCEADD OFFPAGE..6
(-6425 1475);
FORCEPROP 2 LAST $XR0 53 
J 0
(-6674 1475);
DISPLAY 0.638298 (-6674 1475);
PAINT MONO (-6674 1475);
FORCEPROP 2 LAST $XR1 54 
J 0
(-6764 1475);
DISPLAY 0.638298 (-6764 1475);
PAINT MONO (-6764 1475);
FORCEPROP 2 LAST CDS_LIB mstr_standard
J 0
(-6425 1475);
PAINT MONO (-6425 1475);
DISPLAY INVISIBLE (-6425 1475);
FORCEPROP 1 LAST OFFPAGE TRUE
J 0
(-6100 1350);
DISPLAY 1.170213 (-6100 1350);
PAINT GREEN (-6100 1350);
DISPLAY INVISIBLE (-6100 1350);
FORCEPROP 1 LAST COMMENT_BODY TRUE
J 0
(-6325 1400);
DISPLAY 1.170213 (-6325 1400);
PAINT GREEN (-6325 1400);
DISPLAY INVISIBLE (-6325 1400);
FORCEPROP 2 LAST PATH I4
J 0
(-6375 1550);
DISPLAY 1.021277 (-6375 1550);
PAINT ORANGE (-6375 1550);
DISPLAY INVISIBLE (-6375 1550);
FORCEADD TAP..6
(-5575 2425);
FORCEPROP 3 LASTPIN (-5525 2425) SIG_NAME M_F_DQ<18>
J 0
(-5515 2435);
DISPLAY 0.659574 (-5515 2435);
PAINT MONO (-5515 2435);
DISPLAY INVISIBLE (-5515 2435);
FORCEPROP 1 LASTPIN (-5525 2425) BN 18
J 0
(-5577 2433);
DISPLAY 0.617021 (-5577 2433);
PAINT PINK (-5577 2433);
FORCEPROP 2 LAST CDS_LIB mstr_standard
J 0
(-5575 2425);
PAINT MONO (-5575 2425);
DISPLAY INVISIBLE (-5575 2425);
FORCEPROP 1 LAST BODY_TYPE PLUMBING
J 0
(-5575 2375);
DISPLAY 1.595745 (-5575 2375);
PAINT GREEN (-5575 2375);
DISPLAY INVISIBLE (-5575 2375);
FORCEPROP 1 LAST HDL_TAP TRUE
J 0
(-5250 2300);
DISPLAY 1.595745 (-5250 2300);
PAINT GREEN (-5250 2300);
DISPLAY INVISIBLE (-5250 2300);
FORCEPROP 1 LAST PATH I40
J 0
(-5577 2425);
DISPLAY 0.872340 (-5577 2425);
PAINT GREEN (-5577 2425);
DISPLAY INVISIBLE (-5577 2425);
FORCEADD TAP..6
(-5575 2475);
FORCEPROP 3 LASTPIN (-5525 2475) SIG_NAME M_F_DQ<19>
J 0
(-5515 2485);
DISPLAY 0.659574 (-5515 2485);
PAINT MONO (-5515 2485);
DISPLAY INVISIBLE (-5515 2485);
FORCEPROP 1 LASTPIN (-5525 2475) BN 19
J 0
(-5577 2483);
DISPLAY 0.617021 (-5577 2483);
PAINT PINK (-5577 2483);
FORCEPROP 2 LAST CDS_LIB mstr_standard
J 0
(-5575 2475);
PAINT MONO (-5575 2475);
DISPLAY INVISIBLE (-5575 2475);
FORCEPROP 1 LAST BODY_TYPE PLUMBING
J 0
(-5575 2425);
DISPLAY 1.595745 (-5575 2425);
PAINT GREEN (-5575 2425);
DISPLAY INVISIBLE (-5575 2425);
FORCEPROP 1 LAST HDL_TAP TRUE
J 0
(-5250 2350);
DISPLAY 1.595745 (-5250 2350);
PAINT GREEN (-5250 2350);
DISPLAY INVISIBLE (-5250 2350);
FORCEPROP 1 LAST PATH I41
J 0
(-5577 2475);
DISPLAY 0.872340 (-5577 2475);
PAINT GREEN (-5577 2475);
DISPLAY INVISIBLE (-5577 2475);
FORCEADD TAP..6
(-5575 2525);
FORCEPROP 3 LASTPIN (-5525 2525) SIG_NAME M_F_DQ<20>
J 0
(-5515 2535);
DISPLAY 0.659574 (-5515 2535);
PAINT MONO (-5515 2535);
DISPLAY INVISIBLE (-5515 2535);
FORCEPROP 1 LASTPIN (-5525 2525) BN 20
J 0
(-5577 2533);
DISPLAY 0.617021 (-5577 2533);
PAINT PINK (-5577 2533);
FORCEPROP 2 LAST CDS_LIB mstr_standard
J 0
(-5575 2525);
PAINT MONO (-5575 2525);
DISPLAY INVISIBLE (-5575 2525);
FORCEPROP 1 LAST BODY_TYPE PLUMBING
J 0
(-5575 2475);
DISPLAY 1.595745 (-5575 2475);
PAINT GREEN (-5575 2475);
DISPLAY INVISIBLE (-5575 2475);
FORCEPROP 1 LAST HDL_TAP TRUE
J 0
(-5250 2400);
DISPLAY 1.595745 (-5250 2400);
PAINT GREEN (-5250 2400);
DISPLAY INVISIBLE (-5250 2400);
FORCEPROP 1 LAST PATH I42
J 0
(-5577 2525);
DISPLAY 0.872340 (-5577 2525);
PAINT GREEN (-5577 2525);
DISPLAY INVISIBLE (-5577 2525);
FORCEADD TAP..6
(-5575 2575);
FORCEPROP 3 LASTPIN (-5525 2575) SIG_NAME M_F_DQ<21>
J 0
(-5515 2585);
DISPLAY 0.659574 (-5515 2585);
PAINT MONO (-5515 2585);
DISPLAY INVISIBLE (-5515 2585);
FORCEPROP 1 LASTPIN (-5525 2575) BN 21
J 0
(-5577 2583);
DISPLAY 0.617021 (-5577 2583);
PAINT PINK (-5577 2583);
FORCEPROP 2 LAST CDS_LIB mstr_standard
J 0
(-5575 2575);
PAINT MONO (-5575 2575);
DISPLAY INVISIBLE (-5575 2575);
FORCEPROP 1 LAST BODY_TYPE PLUMBING
J 0
(-5575 2525);
DISPLAY 1.595745 (-5575 2525);
PAINT GREEN (-5575 2525);
DISPLAY INVISIBLE (-5575 2525);
FORCEPROP 1 LAST HDL_TAP TRUE
J 0
(-5250 2450);
DISPLAY 1.595745 (-5250 2450);
PAINT GREEN (-5250 2450);
DISPLAY INVISIBLE (-5250 2450);
FORCEPROP 1 LAST PATH I43
J 0
(-5577 2575);
DISPLAY 0.872340 (-5577 2575);
PAINT GREEN (-5577 2575);
DISPLAY INVISIBLE (-5577 2575);
FORCEADD TAP..6
(-5575 2625);
FORCEPROP 3 LASTPIN (-5525 2625) SIG_NAME M_F_DQ<22>
J 0
(-5515 2635);
DISPLAY 0.659574 (-5515 2635);
PAINT MONO (-5515 2635);
DISPLAY INVISIBLE (-5515 2635);
FORCEPROP 1 LASTPIN (-5525 2625) BN 22
J 0
(-5577 2633);
DISPLAY 0.617021 (-5577 2633);
PAINT PINK (-5577 2633);
FORCEPROP 2 LAST CDS_LIB mstr_standard
J 0
(-5575 2625);
PAINT MONO (-5575 2625);
DISPLAY INVISIBLE (-5575 2625);
FORCEPROP 1 LAST BODY_TYPE PLUMBING
J 0
(-5575 2575);
DISPLAY 1.595745 (-5575 2575);
PAINT GREEN (-5575 2575);
DISPLAY INVISIBLE (-5575 2575);
FORCEPROP 1 LAST HDL_TAP TRUE
J 0
(-5250 2500);
DISPLAY 1.595745 (-5250 2500);
PAINT GREEN (-5250 2500);
DISPLAY INVISIBLE (-5250 2500);
FORCEPROP 1 LAST PATH I44
J 0
(-5577 2625);
DISPLAY 0.872340 (-5577 2625);
PAINT GREEN (-5577 2625);
DISPLAY INVISIBLE (-5577 2625);
FORCEADD TAP..6
(-5575 2675);
FORCEPROP 3 LASTPIN (-5525 2675) SIG_NAME M_F_DQ<23>
J 0
(-5515 2685);
DISPLAY 0.659574 (-5515 2685);
PAINT MONO (-5515 2685);
DISPLAY INVISIBLE (-5515 2685);
FORCEPROP 1 LASTPIN (-5525 2675) BN 23
J 0
(-5577 2683);
DISPLAY 0.617021 (-5577 2683);
PAINT PINK (-5577 2683);
FORCEPROP 2 LAST CDS_LIB mstr_standard
J 0
(-5575 2675);
PAINT MONO (-5575 2675);
DISPLAY INVISIBLE (-5575 2675);
FORCEPROP 1 LAST BODY_TYPE PLUMBING
J 0
(-5575 2625);
DISPLAY 1.595745 (-5575 2625);
PAINT GREEN (-5575 2625);
DISPLAY INVISIBLE (-5575 2625);
FORCEPROP 1 LAST HDL_TAP TRUE
J 0
(-5250 2550);
DISPLAY 1.595745 (-5250 2550);
PAINT GREEN (-5250 2550);
DISPLAY INVISIBLE (-5250 2550);
FORCEPROP 1 LAST PATH I45
J 0
(-5577 2675);
DISPLAY 0.872340 (-5577 2675);
PAINT GREEN (-5577 2675);
DISPLAY INVISIBLE (-5577 2675);
FORCEADD TAP..6
(-5575 2725);
FORCEPROP 3 LASTPIN (-5525 2725) SIG_NAME M_F_DQ<24>
J 0
(-5515 2735);
DISPLAY 0.659574 (-5515 2735);
PAINT MONO (-5515 2735);
DISPLAY INVISIBLE (-5515 2735);
FORCEPROP 1 LASTPIN (-5525 2725) BN 24
J 0
(-5577 2733);
DISPLAY 0.617021 (-5577 2733);
PAINT PINK (-5577 2733);
FORCEPROP 2 LAST CDS_LIB mstr_standard
J 0
(-5575 2725);
PAINT MONO (-5575 2725);
DISPLAY INVISIBLE (-5575 2725);
FORCEPROP 1 LAST BODY_TYPE PLUMBING
J 0
(-5575 2675);
DISPLAY 1.595745 (-5575 2675);
PAINT GREEN (-5575 2675);
DISPLAY INVISIBLE (-5575 2675);
FORCEPROP 1 LAST HDL_TAP TRUE
J 0
(-5250 2600);
DISPLAY 1.595745 (-5250 2600);
PAINT GREEN (-5250 2600);
DISPLAY INVISIBLE (-5250 2600);
FORCEPROP 1 LAST PATH I46
J 0
(-5577 2725);
DISPLAY 0.872340 (-5577 2725);
PAINT GREEN (-5577 2725);
DISPLAY INVISIBLE (-5577 2725);
FORCEADD TAP..6
(-5575 2825);
FORCEPROP 3 LASTPIN (-5525 2825) SIG_NAME M_F_DQ<26>
J 0
(-5515 2835);
DISPLAY 0.659574 (-5515 2835);
PAINT MONO (-5515 2835);
DISPLAY INVISIBLE (-5515 2835);
FORCEPROP 1 LASTPIN (-5525 2825) BN 26
J 0
(-5577 2833);
DISPLAY 0.617021 (-5577 2833);
PAINT PINK (-5577 2833);
FORCEPROP 2 LAST CDS_LIB mstr_standard
J 0
(-5575 2825);
PAINT MONO (-5575 2825);
DISPLAY INVISIBLE (-5575 2825);
FORCEPROP 1 LAST BODY_TYPE PLUMBING
J 0
(-5575 2775);
DISPLAY 1.595745 (-5575 2775);
PAINT GREEN (-5575 2775);
DISPLAY INVISIBLE (-5575 2775);
FORCEPROP 1 LAST HDL_TAP TRUE
J 0
(-5250 2700);
DISPLAY 1.595745 (-5250 2700);
PAINT GREEN (-5250 2700);
DISPLAY INVISIBLE (-5250 2700);
FORCEPROP 1 LAST PATH I47
J 0
(-5577 2825);
DISPLAY 0.872340 (-5577 2825);
PAINT GREEN (-5577 2825);
DISPLAY INVISIBLE (-5577 2825);
FORCEADD TAP..6
(-5575 2775);
FORCEPROP 3 LASTPIN (-5525 2775) SIG_NAME M_F_DQ<25>
J 0
(-5515 2785);
DISPLAY 0.659574 (-5515 2785);
PAINT MONO (-5515 2785);
DISPLAY INVISIBLE (-5515 2785);
FORCEPROP 1 LASTPIN (-5525 2775) BN 25
J 0
(-5577 2783);
DISPLAY 0.617021 (-5577 2783);
PAINT PINK (-5577 2783);
FORCEPROP 2 LAST CDS_LIB mstr_standard
J 0
(-5575 2775);
PAINT MONO (-5575 2775);
DISPLAY INVISIBLE (-5575 2775);
FORCEPROP 1 LAST BODY_TYPE PLUMBING
J 0
(-5575 2725);
DISPLAY 1.595745 (-5575 2725);
PAINT GREEN (-5575 2725);
DISPLAY INVISIBLE (-5575 2725);
FORCEPROP 1 LAST HDL_TAP TRUE
J 0
(-5250 2650);
DISPLAY 1.595745 (-5250 2650);
PAINT GREEN (-5250 2650);
DISPLAY INVISIBLE (-5250 2650);
FORCEPROP 1 LAST PATH I48
J 0
(-5577 2775);
DISPLAY 0.872340 (-5577 2775);
PAINT GREEN (-5577 2775);
DISPLAY INVISIBLE (-5577 2775);
FORCEADD TAP..6
(-5575 2875);
FORCEPROP 3 LASTPIN (-5525 2875) SIG_NAME M_F_DQ<27>
J 0
(-5515 2885);
DISPLAY 0.659574 (-5515 2885);
PAINT MONO (-5515 2885);
DISPLAY INVISIBLE (-5515 2885);
FORCEPROP 1 LASTPIN (-5525 2875) BN 27
J 0
(-5577 2883);
DISPLAY 0.617021 (-5577 2883);
PAINT PINK (-5577 2883);
FORCEPROP 2 LAST CDS_LIB mstr_standard
J 0
(-5575 2875);
PAINT MONO (-5575 2875);
DISPLAY INVISIBLE (-5575 2875);
FORCEPROP 1 LAST BODY_TYPE PLUMBING
J 0
(-5575 2825);
DISPLAY 1.595745 (-5575 2825);
PAINT GREEN (-5575 2825);
DISPLAY INVISIBLE (-5575 2825);
FORCEPROP 1 LAST HDL_TAP TRUE
J 0
(-5250 2750);
DISPLAY 1.595745 (-5250 2750);
PAINT GREEN (-5250 2750);
DISPLAY INVISIBLE (-5250 2750);
FORCEPROP 1 LAST PATH I49
J 0
(-5577 2875);
DISPLAY 0.872340 (-5577 2875);
PAINT GREEN (-5577 2875);
DISPLAY INVISIBLE (-5577 2875);
FORCEADD TAP..6
(-5575 625);
FORCEPROP 3 LASTPIN (-5525 625) SIG_NAME M_F_CLK_DN<0>
J 0
(-5515 635);
DISPLAY 0.659574 (-5515 635);
PAINT MONO (-5515 635);
DISPLAY INVISIBLE (-5515 635);
FORCEPROP 1 LASTPIN (-5525 625) BN 0
J 0
(-5577 633);
DISPLAY 0.617021 (-5577 633);
PAINT PINK (-5577 633);
FORCEPROP 2 LAST CDS_LIB mstr_standard
J 0
(-5575 625);
PAINT MONO (-5575 625);
DISPLAY INVISIBLE (-5575 625);
FORCEPROP 1 LAST BODY_TYPE PLUMBING
J 0
(-5575 575);
DISPLAY 1.595745 (-5575 575);
PAINT GREEN (-5575 575);
DISPLAY INVISIBLE (-5575 575);
FORCEPROP 1 LAST HDL_TAP TRUE
J 0
(-5250 500);
DISPLAY 1.595745 (-5250 500);
PAINT GREEN (-5250 500);
DISPLAY INVISIBLE (-5250 500);
FORCEPROP 1 LAST PATH I5
J 0
(-5577 625);
DISPLAY 0.872340 (-5577 625);
PAINT GREEN (-5577 625);
DISPLAY INVISIBLE (-5577 625);
FORCEADD TAP..6
(-5575 2925);
FORCEPROP 3 LASTPIN (-5525 2925) SIG_NAME M_F_DQ<28>
J 0
(-5515 2935);
DISPLAY 0.659574 (-5515 2935);
PAINT MONO (-5515 2935);
DISPLAY INVISIBLE (-5515 2935);
FORCEPROP 1 LASTPIN (-5525 2925) BN 28
J 0
(-5577 2933);
DISPLAY 0.617021 (-5577 2933);
PAINT PINK (-5577 2933);
FORCEPROP 2 LAST CDS_LIB mstr_standard
J 0
(-5575 2925);
PAINT MONO (-5575 2925);
DISPLAY INVISIBLE (-5575 2925);
FORCEPROP 1 LAST BODY_TYPE PLUMBING
J 0
(-5575 2875);
DISPLAY 1.595745 (-5575 2875);
PAINT GREEN (-5575 2875);
DISPLAY INVISIBLE (-5575 2875);
FORCEPROP 1 LAST HDL_TAP TRUE
J 0
(-5250 2800);
DISPLAY 1.595745 (-5250 2800);
PAINT GREEN (-5250 2800);
DISPLAY INVISIBLE (-5250 2800);
FORCEPROP 1 LAST PATH I50
J 0
(-5577 2925);
DISPLAY 0.872340 (-5577 2925);
PAINT GREEN (-5577 2925);
DISPLAY INVISIBLE (-5577 2925);
FORCEADD TAP..6
(-5575 2975);
FORCEPROP 3 LASTPIN (-5525 2975) SIG_NAME M_F_DQ<29>
J 0
(-5515 2985);
DISPLAY 0.659574 (-5515 2985);
PAINT MONO (-5515 2985);
DISPLAY INVISIBLE (-5515 2985);
FORCEPROP 1 LASTPIN (-5525 2975) BN 29
J 0
(-5577 2983);
DISPLAY 0.617021 (-5577 2983);
PAINT PINK (-5577 2983);
FORCEPROP 2 LAST CDS_LIB mstr_standard
J 0
(-5575 2975);
PAINT MONO (-5575 2975);
DISPLAY INVISIBLE (-5575 2975);
FORCEPROP 1 LAST BODY_TYPE PLUMBING
J 0
(-5575 2925);
DISPLAY 1.595745 (-5575 2925);
PAINT GREEN (-5575 2925);
DISPLAY INVISIBLE (-5575 2925);
FORCEPROP 1 LAST HDL_TAP TRUE
J 0
(-5250 2850);
DISPLAY 1.595745 (-5250 2850);
PAINT GREEN (-5250 2850);
DISPLAY INVISIBLE (-5250 2850);
FORCEPROP 1 LAST PATH I51
J 0
(-5577 2975);
DISPLAY 0.872340 (-5577 2975);
PAINT GREEN (-5577 2975);
DISPLAY INVISIBLE (-5577 2975);
FORCEADD TAP..6
(-5575 3075);
FORCEPROP 3 LASTPIN (-5525 3075) SIG_NAME M_F_DQ<31>
J 0
(-5515 3085);
DISPLAY 0.659574 (-5515 3085);
PAINT MONO (-5515 3085);
DISPLAY INVISIBLE (-5515 3085);
FORCEPROP 1 LASTPIN (-5525 3075) BN 31
J 0
(-5577 3083);
DISPLAY 0.617021 (-5577 3083);
PAINT PINK (-5577 3083);
FORCEPROP 2 LAST CDS_LIB mstr_standard
J 0
(-5575 3075);
PAINT MONO (-5575 3075);
DISPLAY INVISIBLE (-5575 3075);
FORCEPROP 1 LAST BODY_TYPE PLUMBING
J 0
(-5575 3025);
DISPLAY 1.595745 (-5575 3025);
PAINT GREEN (-5575 3025);
DISPLAY INVISIBLE (-5575 3025);
FORCEPROP 1 LAST HDL_TAP TRUE
J 0
(-5250 2950);
DISPLAY 1.595745 (-5250 2950);
PAINT GREEN (-5250 2950);
DISPLAY INVISIBLE (-5250 2950);
FORCEPROP 1 LAST PATH I52
J 0
(-5577 3075);
DISPLAY 0.872340 (-5577 3075);
PAINT GREEN (-5577 3075);
DISPLAY INVISIBLE (-5577 3075);
FORCEADD TAP..6
(-5575 3025);
FORCEPROP 3 LASTPIN (-5525 3025) SIG_NAME M_F_DQ<30>
J 0
(-5515 3035);
DISPLAY 0.659574 (-5515 3035);
PAINT MONO (-5515 3035);
DISPLAY INVISIBLE (-5515 3035);
FORCEPROP 1 LASTPIN (-5525 3025) BN 30
J 0
(-5577 3033);
DISPLAY 0.617021 (-5577 3033);
PAINT PINK (-5577 3033);
FORCEPROP 2 LAST CDS_LIB mstr_standard
J 0
(-5575 3025);
PAINT MONO (-5575 3025);
DISPLAY INVISIBLE (-5575 3025);
FORCEPROP 1 LAST BODY_TYPE PLUMBING
J 0
(-5575 2975);
DISPLAY 1.595745 (-5575 2975);
PAINT GREEN (-5575 2975);
DISPLAY INVISIBLE (-5575 2975);
FORCEPROP 1 LAST HDL_TAP TRUE
J 0
(-5250 2900);
DISPLAY 1.595745 (-5250 2900);
PAINT GREEN (-5250 2900);
DISPLAY INVISIBLE (-5250 2900);
FORCEPROP 1 LAST PATH I53
J 0
(-5577 3025);
DISPLAY 0.872340 (-5577 3025);
PAINT GREEN (-5577 3025);
DISPLAY INVISIBLE (-5577 3025);
FORCEADD TAP..6
(-5575 3125);
FORCEPROP 3 LASTPIN (-5525 3125) SIG_NAME M_F_DQ<32>
J 0
(-5515 3135);
DISPLAY 0.659574 (-5515 3135);
PAINT MONO (-5515 3135);
DISPLAY INVISIBLE (-5515 3135);
FORCEPROP 1 LASTPIN (-5525 3125) BN 32
J 0
(-5577 3133);
DISPLAY 0.617021 (-5577 3133);
PAINT PINK (-5577 3133);
FORCEPROP 2 LAST CDS_LIB mstr_standard
J 0
(-5575 3125);
PAINT MONO (-5575 3125);
DISPLAY INVISIBLE (-5575 3125);
FORCEPROP 1 LAST BODY_TYPE PLUMBING
J 0
(-5575 3075);
DISPLAY 1.595745 (-5575 3075);
PAINT GREEN (-5575 3075);
DISPLAY INVISIBLE (-5575 3075);
FORCEPROP 1 LAST HDL_TAP TRUE
J 0
(-5250 3000);
DISPLAY 1.595745 (-5250 3000);
PAINT GREEN (-5250 3000);
DISPLAY INVISIBLE (-5250 3000);
FORCEPROP 1 LAST PATH I54
J 0
(-5577 3125);
DISPLAY 0.872340 (-5577 3125);
PAINT GREEN (-5577 3125);
DISPLAY INVISIBLE (-5577 3125);
FORCEADD TAP..6
(-5575 3175);
FORCEPROP 3 LASTPIN (-5525 3175) SIG_NAME M_F_DQ<33>
J 0
(-5515 3185);
DISPLAY 0.659574 (-5515 3185);
PAINT MONO (-5515 3185);
DISPLAY INVISIBLE (-5515 3185);
FORCEPROP 1 LASTPIN (-5525 3175) BN 33
J 0
(-5577 3183);
DISPLAY 0.617021 (-5577 3183);
PAINT PINK (-5577 3183);
FORCEPROP 2 LAST CDS_LIB mstr_standard
J 0
(-5575 3175);
PAINT MONO (-5575 3175);
DISPLAY INVISIBLE (-5575 3175);
FORCEPROP 1 LAST BODY_TYPE PLUMBING
J 0
(-5575 3125);
DISPLAY 1.595745 (-5575 3125);
PAINT GREEN (-5575 3125);
DISPLAY INVISIBLE (-5575 3125);
FORCEPROP 1 LAST HDL_TAP TRUE
J 0
(-5250 3050);
DISPLAY 1.595745 (-5250 3050);
PAINT GREEN (-5250 3050);
DISPLAY INVISIBLE (-5250 3050);
FORCEPROP 1 LAST PATH I55
J 0
(-5577 3175);
DISPLAY 0.872340 (-5577 3175);
PAINT GREEN (-5577 3175);
DISPLAY INVISIBLE (-5577 3175);
FORCEADD TAP..6
(-5575 3225);
FORCEPROP 3 LASTPIN (-5525 3225) SIG_NAME M_F_DQ<34>
J 0
(-5515 3235);
DISPLAY 0.659574 (-5515 3235);
PAINT MONO (-5515 3235);
DISPLAY INVISIBLE (-5515 3235);
FORCEPROP 1 LASTPIN (-5525 3225) BN 34
J 0
(-5577 3233);
DISPLAY 0.617021 (-5577 3233);
PAINT PINK (-5577 3233);
FORCEPROP 2 LAST CDS_LIB mstr_standard
J 0
(-5575 3225);
PAINT MONO (-5575 3225);
DISPLAY INVISIBLE (-5575 3225);
FORCEPROP 1 LAST BODY_TYPE PLUMBING
J 0
(-5575 3175);
DISPLAY 1.595745 (-5575 3175);
PAINT GREEN (-5575 3175);
DISPLAY INVISIBLE (-5575 3175);
FORCEPROP 1 LAST HDL_TAP TRUE
J 0
(-5250 3100);
DISPLAY 1.595745 (-5250 3100);
PAINT GREEN (-5250 3100);
DISPLAY INVISIBLE (-5250 3100);
FORCEPROP 1 LAST PATH I56
J 0
(-5577 3225);
DISPLAY 0.872340 (-5577 3225);
PAINT GREEN (-5577 3225);
DISPLAY INVISIBLE (-5577 3225);
FORCEADD TAP..6
(-5575 3275);
FORCEPROP 3 LASTPIN (-5525 3275) SIG_NAME M_F_DQ<35>
J 0
(-5515 3285);
DISPLAY 0.659574 (-5515 3285);
PAINT MONO (-5515 3285);
DISPLAY INVISIBLE (-5515 3285);
FORCEPROP 1 LASTPIN (-5525 3275) BN 35
J 0
(-5577 3283);
DISPLAY 0.617021 (-5577 3283);
PAINT PINK (-5577 3283);
FORCEPROP 2 LAST CDS_LIB mstr_standard
J 0
(-5575 3275);
PAINT MONO (-5575 3275);
DISPLAY INVISIBLE (-5575 3275);
FORCEPROP 1 LAST BODY_TYPE PLUMBING
J 0
(-5575 3225);
DISPLAY 1.595745 (-5575 3225);
PAINT GREEN (-5575 3225);
DISPLAY INVISIBLE (-5575 3225);
FORCEPROP 1 LAST HDL_TAP TRUE
J 0
(-5250 3150);
DISPLAY 1.595745 (-5250 3150);
PAINT GREEN (-5250 3150);
DISPLAY INVISIBLE (-5250 3150);
FORCEPROP 1 LAST PATH I57
J 0
(-5577 3275);
DISPLAY 0.872340 (-5577 3275);
PAINT GREEN (-5577 3275);
DISPLAY INVISIBLE (-5577 3275);
FORCEADD TAP..6
(-5575 3325);
FORCEPROP 3 LASTPIN (-5525 3325) SIG_NAME M_F_DQ<36>
J 0
(-5515 3335);
DISPLAY 0.659574 (-5515 3335);
PAINT MONO (-5515 3335);
DISPLAY INVISIBLE (-5515 3335);
FORCEPROP 1 LASTPIN (-5525 3325) BN 36
J 0
(-5577 3333);
DISPLAY 0.617021 (-5577 3333);
PAINT PINK (-5577 3333);
FORCEPROP 2 LAST CDS_LIB mstr_standard
J 0
(-5575 3325);
PAINT MONO (-5575 3325);
DISPLAY INVISIBLE (-5575 3325);
FORCEPROP 1 LAST BODY_TYPE PLUMBING
J 0
(-5575 3275);
DISPLAY 1.595745 (-5575 3275);
PAINT GREEN (-5575 3275);
DISPLAY INVISIBLE (-5575 3275);
FORCEPROP 1 LAST HDL_TAP TRUE
J 0
(-5250 3200);
DISPLAY 1.595745 (-5250 3200);
PAINT GREEN (-5250 3200);
DISPLAY INVISIBLE (-5250 3200);
FORCEPROP 1 LAST PATH I58
J 0
(-5577 3325);
DISPLAY 0.872340 (-5577 3325);
PAINT GREEN (-5577 3325);
DISPLAY INVISIBLE (-5577 3325);
FORCEADD TAP..6
(-5575 3375);
FORCEPROP 3 LASTPIN (-5525 3375) SIG_NAME M_F_DQ<37>
J 0
(-5515 3385);
DISPLAY 0.659574 (-5515 3385);
PAINT MONO (-5515 3385);
DISPLAY INVISIBLE (-5515 3385);
FORCEPROP 1 LASTPIN (-5525 3375) BN 37
J 0
(-5577 3383);
DISPLAY 0.617021 (-5577 3383);
PAINT PINK (-5577 3383);
FORCEPROP 2 LAST CDS_LIB mstr_standard
J 0
(-5575 3375);
PAINT MONO (-5575 3375);
DISPLAY INVISIBLE (-5575 3375);
FORCEPROP 1 LAST BODY_TYPE PLUMBING
J 0
(-5575 3325);
DISPLAY 1.595745 (-5575 3325);
PAINT GREEN (-5575 3325);
DISPLAY INVISIBLE (-5575 3325);
FORCEPROP 1 LAST HDL_TAP TRUE
J 0
(-5250 3250);
DISPLAY 1.595745 (-5250 3250);
PAINT GREEN (-5250 3250);
DISPLAY INVISIBLE (-5250 3250);
FORCEPROP 1 LAST PATH I59
J 0
(-5577 3375);
DISPLAY 0.872340 (-5577 3375);
PAINT GREEN (-5577 3375);
DISPLAY INVISIBLE (-5577 3375);
FORCEADD TAP..6
(-5575 675);
FORCEPROP 3 LASTPIN (-5525 675) SIG_NAME M_F_CLK_DN<1>
J 0
(-5515 685);
DISPLAY 0.659574 (-5515 685);
PAINT MONO (-5515 685);
DISPLAY INVISIBLE (-5515 685);
FORCEPROP 1 LASTPIN (-5525 675) BN 1
J 0
(-5577 683);
DISPLAY 0.617021 (-5577 683);
PAINT PINK (-5577 683);
FORCEPROP 2 LAST CDS_LIB mstr_standard
J 0
(-5575 675);
PAINT MONO (-5575 675);
DISPLAY INVISIBLE (-5575 675);
FORCEPROP 1 LAST BODY_TYPE PLUMBING
J 0
(-5575 625);
DISPLAY 1.595745 (-5575 625);
PAINT GREEN (-5575 625);
DISPLAY INVISIBLE (-5575 625);
FORCEPROP 1 LAST HDL_TAP TRUE
J 0
(-5250 550);
DISPLAY 1.595745 (-5250 550);
PAINT GREEN (-5250 550);
DISPLAY INVISIBLE (-5250 550);
FORCEPROP 1 LAST PATH I6
J 0
(-5577 675);
DISPLAY 0.872340 (-5577 675);
PAINT GREEN (-5577 675);
DISPLAY INVISIBLE (-5577 675);
FORCEADD TAP..6
(-5575 3425);
FORCEPROP 3 LASTPIN (-5525 3425) SIG_NAME M_F_DQ<38>
J 0
(-5515 3435);
DISPLAY 0.659574 (-5515 3435);
PAINT MONO (-5515 3435);
DISPLAY INVISIBLE (-5515 3435);
FORCEPROP 1 LASTPIN (-5525 3425) BN 38
J 0
(-5577 3433);
DISPLAY 0.617021 (-5577 3433);
PAINT PINK (-5577 3433);
FORCEPROP 2 LAST CDS_LIB mstr_standard
J 0
(-5575 3425);
PAINT MONO (-5575 3425);
DISPLAY INVISIBLE (-5575 3425);
FORCEPROP 1 LAST BODY_TYPE PLUMBING
J 0
(-5575 3375);
DISPLAY 1.595745 (-5575 3375);
PAINT GREEN (-5575 3375);
DISPLAY INVISIBLE (-5575 3375);
FORCEPROP 1 LAST HDL_TAP TRUE
J 0
(-5250 3300);
DISPLAY 1.595745 (-5250 3300);
PAINT GREEN (-5250 3300);
DISPLAY INVISIBLE (-5250 3300);
FORCEPROP 1 LAST PATH I60
J 0
(-5577 3425);
DISPLAY 0.872340 (-5577 3425);
PAINT GREEN (-5577 3425);
DISPLAY INVISIBLE (-5577 3425);
FORCEADD TAP..6
(-5575 3475);
FORCEPROP 3 LASTPIN (-5525 3475) SIG_NAME M_F_DQ<39>
J 0
(-5515 3485);
DISPLAY 0.659574 (-5515 3485);
PAINT MONO (-5515 3485);
DISPLAY INVISIBLE (-5515 3485);
FORCEPROP 1 LASTPIN (-5525 3475) BN 39
J 0
(-5577 3483);
DISPLAY 0.617021 (-5577 3483);
PAINT PINK (-5577 3483);
FORCEPROP 2 LAST CDS_LIB mstr_standard
J 0
(-5575 3475);
PAINT MONO (-5575 3475);
DISPLAY INVISIBLE (-5575 3475);
FORCEPROP 1 LAST BODY_TYPE PLUMBING
J 0
(-5575 3425);
DISPLAY 1.595745 (-5575 3425);
PAINT GREEN (-5575 3425);
DISPLAY INVISIBLE (-5575 3425);
FORCEPROP 1 LAST HDL_TAP TRUE
J 0
(-5250 3350);
DISPLAY 1.595745 (-5250 3350);
PAINT GREEN (-5250 3350);
DISPLAY INVISIBLE (-5250 3350);
FORCEPROP 1 LAST PATH I61
J 0
(-5577 3475);
DISPLAY 0.872340 (-5577 3475);
PAINT GREEN (-5577 3475);
DISPLAY INVISIBLE (-5577 3475);
FORCEADD TAP..6
(-5575 3525);
FORCEPROP 3 LASTPIN (-5525 3525) SIG_NAME M_F_DQ<40>
J 0
(-5515 3535);
DISPLAY 0.659574 (-5515 3535);
PAINT MONO (-5515 3535);
DISPLAY INVISIBLE (-5515 3535);
FORCEPROP 1 LASTPIN (-5525 3525) BN 40
J 0
(-5577 3533);
DISPLAY 0.617021 (-5577 3533);
PAINT PINK (-5577 3533);
FORCEPROP 2 LAST CDS_LIB mstr_standard
J 0
(-5575 3525);
PAINT MONO (-5575 3525);
DISPLAY INVISIBLE (-5575 3525);
FORCEPROP 1 LAST BODY_TYPE PLUMBING
J 0
(-5575 3475);
DISPLAY 1.595745 (-5575 3475);
PAINT GREEN (-5575 3475);
DISPLAY INVISIBLE (-5575 3475);
FORCEPROP 1 LAST HDL_TAP TRUE
J 0
(-5250 3400);
DISPLAY 1.595745 (-5250 3400);
PAINT GREEN (-5250 3400);
DISPLAY INVISIBLE (-5250 3400);
FORCEPROP 1 LAST PATH I62
J 0
(-5577 3525);
DISPLAY 0.872340 (-5577 3525);
PAINT GREEN (-5577 3525);
DISPLAY INVISIBLE (-5577 3525);
FORCEADD TAP..6
(-5575 3575);
FORCEPROP 3 LASTPIN (-5525 3575) SIG_NAME M_F_DQ<41>
J 0
(-5515 3585);
DISPLAY 0.659574 (-5515 3585);
PAINT MONO (-5515 3585);
DISPLAY INVISIBLE (-5515 3585);
FORCEPROP 1 LASTPIN (-5525 3575) BN 41
J 0
(-5577 3583);
DISPLAY 0.617021 (-5577 3583);
PAINT PINK (-5577 3583);
FORCEPROP 2 LAST CDS_LIB mstr_standard
J 0
(-5575 3575);
PAINT MONO (-5575 3575);
DISPLAY INVISIBLE (-5575 3575);
FORCEPROP 1 LAST BODY_TYPE PLUMBING
J 0
(-5575 3525);
DISPLAY 1.595745 (-5575 3525);
PAINT GREEN (-5575 3525);
DISPLAY INVISIBLE (-5575 3525);
FORCEPROP 1 LAST HDL_TAP TRUE
J 0
(-5250 3450);
DISPLAY 1.595745 (-5250 3450);
PAINT GREEN (-5250 3450);
DISPLAY INVISIBLE (-5250 3450);
FORCEPROP 1 LAST PATH I63
J 0
(-5577 3575);
DISPLAY 0.872340 (-5577 3575);
PAINT GREEN (-5577 3575);
DISPLAY INVISIBLE (-5577 3575);
FORCEADD TAP..6
(-5575 3625);
FORCEPROP 3 LASTPIN (-5525 3625) SIG_NAME M_F_DQ<42>
J 0
(-5515 3635);
DISPLAY 0.659574 (-5515 3635);
PAINT MONO (-5515 3635);
DISPLAY INVISIBLE (-5515 3635);
FORCEPROP 1 LASTPIN (-5525 3625) BN 42
J 0
(-5577 3633);
DISPLAY 0.617021 (-5577 3633);
PAINT PINK (-5577 3633);
FORCEPROP 2 LAST CDS_LIB mstr_standard
J 0
(-5575 3625);
PAINT MONO (-5575 3625);
DISPLAY INVISIBLE (-5575 3625);
FORCEPROP 1 LAST BODY_TYPE PLUMBING
J 0
(-5575 3575);
DISPLAY 1.595745 (-5575 3575);
PAINT GREEN (-5575 3575);
DISPLAY INVISIBLE (-5575 3575);
FORCEPROP 1 LAST HDL_TAP TRUE
J 0
(-5250 3500);
DISPLAY 1.595745 (-5250 3500);
PAINT GREEN (-5250 3500);
DISPLAY INVISIBLE (-5250 3500);
FORCEPROP 1 LAST PATH I64
J 0
(-5577 3625);
DISPLAY 0.872340 (-5577 3625);
PAINT GREEN (-5577 3625);
DISPLAY INVISIBLE (-5577 3625);
FORCEADD TAP..6
(-5575 3675);
FORCEPROP 3 LASTPIN (-5525 3675) SIG_NAME M_F_DQ<43>
J 0
(-5515 3685);
DISPLAY 0.659574 (-5515 3685);
PAINT MONO (-5515 3685);
DISPLAY INVISIBLE (-5515 3685);
FORCEPROP 1 LASTPIN (-5525 3675) BN 43
J 0
(-5577 3683);
DISPLAY 0.617021 (-5577 3683);
PAINT PINK (-5577 3683);
FORCEPROP 2 LAST CDS_LIB mstr_standard
J 0
(-5575 3675);
PAINT MONO (-5575 3675);
DISPLAY INVISIBLE (-5575 3675);
FORCEPROP 1 LAST BODY_TYPE PLUMBING
J 0
(-5575 3625);
DISPLAY 1.595745 (-5575 3625);
PAINT GREEN (-5575 3625);
DISPLAY INVISIBLE (-5575 3625);
FORCEPROP 1 LAST HDL_TAP TRUE
J 0
(-5250 3550);
DISPLAY 1.595745 (-5250 3550);
PAINT GREEN (-5250 3550);
DISPLAY INVISIBLE (-5250 3550);
FORCEPROP 1 LAST PATH I65
J 0
(-5577 3675);
DISPLAY 0.872340 (-5577 3675);
PAINT GREEN (-5577 3675);
DISPLAY INVISIBLE (-5577 3675);
FORCEADD TAP..6
(-5575 3725);
FORCEPROP 3 LASTPIN (-5525 3725) SIG_NAME M_F_DQ<44>
J 0
(-5515 3735);
DISPLAY 0.659574 (-5515 3735);
PAINT MONO (-5515 3735);
DISPLAY INVISIBLE (-5515 3735);
FORCEPROP 1 LASTPIN (-5525 3725) BN 44
J 0
(-5577 3733);
DISPLAY 0.617021 (-5577 3733);
PAINT PINK (-5577 3733);
FORCEPROP 2 LAST CDS_LIB mstr_standard
J 0
(-5575 3725);
PAINT MONO (-5575 3725);
DISPLAY INVISIBLE (-5575 3725);
FORCEPROP 1 LAST BODY_TYPE PLUMBING
J 0
(-5575 3675);
DISPLAY 1.595745 (-5575 3675);
PAINT GREEN (-5575 3675);
DISPLAY INVISIBLE (-5575 3675);
FORCEPROP 1 LAST HDL_TAP TRUE
J 0
(-5250 3600);
DISPLAY 1.595745 (-5250 3600);
PAINT GREEN (-5250 3600);
DISPLAY INVISIBLE (-5250 3600);
FORCEPROP 1 LAST PATH I66
J 0
(-5577 3725);
DISPLAY 0.872340 (-5577 3725);
PAINT GREEN (-5577 3725);
DISPLAY INVISIBLE (-5577 3725);
FORCEADD TAP..6
(-5575 3775);
FORCEPROP 3 LASTPIN (-5525 3775) SIG_NAME M_F_DQ<45>
J 0
(-5515 3785);
DISPLAY 0.659574 (-5515 3785);
PAINT MONO (-5515 3785);
DISPLAY INVISIBLE (-5515 3785);
FORCEPROP 1 LASTPIN (-5525 3775) BN 45
J 0
(-5577 3783);
DISPLAY 0.617021 (-5577 3783);
PAINT PINK (-5577 3783);
FORCEPROP 2 LAST CDS_LIB mstr_standard
J 0
(-5575 3775);
PAINT MONO (-5575 3775);
DISPLAY INVISIBLE (-5575 3775);
FORCEPROP 1 LAST BODY_TYPE PLUMBING
J 0
(-5575 3725);
DISPLAY 1.595745 (-5575 3725);
PAINT GREEN (-5575 3725);
DISPLAY INVISIBLE (-5575 3725);
FORCEPROP 1 LAST HDL_TAP TRUE
J 0
(-5250 3650);
DISPLAY 1.595745 (-5250 3650);
PAINT GREEN (-5250 3650);
DISPLAY INVISIBLE (-5250 3650);
FORCEPROP 1 LAST PATH I67
J 0
(-5577 3775);
DISPLAY 0.872340 (-5577 3775);
PAINT GREEN (-5577 3775);
DISPLAY INVISIBLE (-5577 3775);
FORCEADD TAP..6
(-5575 3825);
FORCEPROP 3 LASTPIN (-5525 3825) SIG_NAME M_F_DQ<46>
J 0
(-5515 3835);
DISPLAY 0.659574 (-5515 3835);
PAINT MONO (-5515 3835);
DISPLAY INVISIBLE (-5515 3835);
FORCEPROP 1 LASTPIN (-5525 3825) BN 46
J 0
(-5577 3833);
DISPLAY 0.617021 (-5577 3833);
PAINT PINK (-5577 3833);
FORCEPROP 2 LAST CDS_LIB mstr_standard
J 0
(-5575 3825);
PAINT MONO (-5575 3825);
DISPLAY INVISIBLE (-5575 3825);
FORCEPROP 1 LAST BODY_TYPE PLUMBING
J 0
(-5575 3775);
DISPLAY 1.595745 (-5575 3775);
PAINT GREEN (-5575 3775);
DISPLAY INVISIBLE (-5575 3775);
FORCEPROP 1 LAST HDL_TAP TRUE
J 0
(-5250 3700);
DISPLAY 1.595745 (-5250 3700);
PAINT GREEN (-5250 3700);
DISPLAY INVISIBLE (-5250 3700);
FORCEPROP 1 LAST PATH I68
J 0
(-5577 3825);
DISPLAY 0.872340 (-5577 3825);
PAINT GREEN (-5577 3825);
DISPLAY INVISIBLE (-5577 3825);
FORCEADD TAP..6
(-5575 3875);
FORCEPROP 3 LASTPIN (-5525 3875) SIG_NAME M_F_DQ<47>
J 0
(-5515 3885);
DISPLAY 0.659574 (-5515 3885);
PAINT MONO (-5515 3885);
DISPLAY INVISIBLE (-5515 3885);
FORCEPROP 1 LASTPIN (-5525 3875) BN 47
J 0
(-5577 3883);
DISPLAY 0.617021 (-5577 3883);
PAINT PINK (-5577 3883);
FORCEPROP 2 LAST CDS_LIB mstr_standard
J 0
(-5575 3875);
PAINT MONO (-5575 3875);
DISPLAY INVISIBLE (-5575 3875);
FORCEPROP 1 LAST BODY_TYPE PLUMBING
J 0
(-5575 3825);
DISPLAY 1.595745 (-5575 3825);
PAINT GREEN (-5575 3825);
DISPLAY INVISIBLE (-5575 3825);
FORCEPROP 1 LAST HDL_TAP TRUE
J 0
(-5250 3750);
DISPLAY 1.595745 (-5250 3750);
PAINT GREEN (-5250 3750);
DISPLAY INVISIBLE (-5250 3750);
FORCEPROP 1 LAST PATH I69
J 0
(-5577 3875);
DISPLAY 0.872340 (-5577 3875);
PAINT GREEN (-5577 3875);
DISPLAY INVISIBLE (-5577 3875);
FORCEADD TAP..6
(-5575 775);
FORCEPROP 3 LASTPIN (-5525 775) SIG_NAME M_F_CLK_DN<3>
J 0
(-5515 785);
DISPLAY 0.659574 (-5515 785);
PAINT MONO (-5515 785);
DISPLAY INVISIBLE (-5515 785);
FORCEPROP 1 LASTPIN (-5525 775) BN 3
J 0
(-5577 783);
DISPLAY 0.617021 (-5577 783);
PAINT PINK (-5577 783);
FORCEPROP 2 LAST CDS_LIB mstr_standard
J 0
(-5575 775);
PAINT MONO (-5575 775);
DISPLAY INVISIBLE (-5575 775);
FORCEPROP 1 LAST BODY_TYPE PLUMBING
J 0
(-5575 725);
DISPLAY 1.595745 (-5575 725);
PAINT GREEN (-5575 725);
DISPLAY INVISIBLE (-5575 725);
FORCEPROP 1 LAST HDL_TAP TRUE
J 0
(-5250 650);
DISPLAY 1.595745 (-5250 650);
PAINT GREEN (-5250 650);
DISPLAY INVISIBLE (-5250 650);
FORCEPROP 1 LAST PATH I7
J 0
(-5577 775);
DISPLAY 0.872340 (-5577 775);
PAINT GREEN (-5577 775);
DISPLAY INVISIBLE (-5577 775);
FORCEADD TAP..6
(-5575 3925);
FORCEPROP 3 LASTPIN (-5525 3925) SIG_NAME M_F_DQ<48>
J 0
(-5515 3935);
DISPLAY 0.659574 (-5515 3935);
PAINT MONO (-5515 3935);
DISPLAY INVISIBLE (-5515 3935);
FORCEPROP 1 LASTPIN (-5525 3925) BN 48
J 0
(-5577 3933);
DISPLAY 0.617021 (-5577 3933);
PAINT PINK (-5577 3933);
FORCEPROP 2 LAST CDS_LIB mstr_standard
J 0
(-5575 3925);
PAINT MONO (-5575 3925);
DISPLAY INVISIBLE (-5575 3925);
FORCEPROP 1 LAST BODY_TYPE PLUMBING
J 0
(-5575 3875);
DISPLAY 1.595745 (-5575 3875);
PAINT GREEN (-5575 3875);
DISPLAY INVISIBLE (-5575 3875);
FORCEPROP 1 LAST HDL_TAP TRUE
J 0
(-5250 3800);
DISPLAY 1.595745 (-5250 3800);
PAINT GREEN (-5250 3800);
DISPLAY INVISIBLE (-5250 3800);
FORCEPROP 1 LAST PATH I70
J 0
(-5577 3925);
DISPLAY 0.872340 (-5577 3925);
PAINT GREEN (-5577 3925);
DISPLAY INVISIBLE (-5577 3925);
FORCEADD TAP..6
(-5575 3975);
FORCEPROP 3 LASTPIN (-5525 3975) SIG_NAME M_F_DQ<49>
J 0
(-5515 3985);
DISPLAY 0.659574 (-5515 3985);
PAINT MONO (-5515 3985);
DISPLAY INVISIBLE (-5515 3985);
FORCEPROP 1 LASTPIN (-5525 3975) BN 49
J 0
(-5577 3983);
DISPLAY 0.617021 (-5577 3983);
PAINT PINK (-5577 3983);
FORCEPROP 2 LAST CDS_LIB mstr_standard
J 0
(-5575 3975);
PAINT MONO (-5575 3975);
DISPLAY INVISIBLE (-5575 3975);
FORCEPROP 1 LAST BODY_TYPE PLUMBING
J 0
(-5575 3925);
DISPLAY 1.595745 (-5575 3925);
PAINT GREEN (-5575 3925);
DISPLAY INVISIBLE (-5575 3925);
FORCEPROP 1 LAST HDL_TAP TRUE
J 0
(-5250 3850);
DISPLAY 1.595745 (-5250 3850);
PAINT GREEN (-5250 3850);
DISPLAY INVISIBLE (-5250 3850);
FORCEPROP 1 LAST PATH I71
J 0
(-5577 3975);
DISPLAY 0.872340 (-5577 3975);
PAINT GREEN (-5577 3975);
DISPLAY INVISIBLE (-5577 3975);
FORCEADD TAP..6
(-5575 4025);
FORCEPROP 3 LASTPIN (-5525 4025) SIG_NAME M_F_DQ<50>
J 0
(-5515 4035);
DISPLAY 0.659574 (-5515 4035);
PAINT MONO (-5515 4035);
DISPLAY INVISIBLE (-5515 4035);
FORCEPROP 1 LASTPIN (-5525 4025) BN 50
J 0
(-5577 4033);
DISPLAY 0.617021 (-5577 4033);
PAINT PINK (-5577 4033);
FORCEPROP 2 LAST CDS_LIB mstr_standard
J 0
(-5575 4025);
PAINT MONO (-5575 4025);
DISPLAY INVISIBLE (-5575 4025);
FORCEPROP 1 LAST BODY_TYPE PLUMBING
J 0
(-5575 3975);
DISPLAY 1.595745 (-5575 3975);
PAINT GREEN (-5575 3975);
DISPLAY INVISIBLE (-5575 3975);
FORCEPROP 1 LAST HDL_TAP TRUE
J 0
(-5250 3900);
DISPLAY 1.595745 (-5250 3900);
PAINT GREEN (-5250 3900);
DISPLAY INVISIBLE (-5250 3900);
FORCEPROP 1 LAST PATH I72
J 0
(-5577 4025);
DISPLAY 0.872340 (-5577 4025);
PAINT GREEN (-5577 4025);
DISPLAY INVISIBLE (-5577 4025);
FORCEADD OFFPAGE..6
(-6425 4800);
FORCEPROP 2 LAST $XR0 53 
J 0
(-6674 4800);
DISPLAY 0.638298 (-6674 4800);
PAINT MONO (-6674 4800);
FORCEPROP 2 LAST $XR1 54 
J 0
(-6764 4800);
DISPLAY 0.638298 (-6764 4800);
PAINT MONO (-6764 4800);
FORCEPROP 2 LAST CDS_LIB mstr_standard
J 0
(-6425 4800);
PAINT MONO (-6425 4800);
DISPLAY INVISIBLE (-6425 4800);
FORCEPROP 1 LAST OFFPAGE TRUE
J 0
(-6100 4675);
DISPLAY 1.170213 (-6100 4675);
PAINT GREEN (-6100 4675);
DISPLAY INVISIBLE (-6100 4675);
FORCEPROP 1 LAST COMMENT_BODY TRUE
J 0
(-6325 4725);
DISPLAY 1.170213 (-6325 4725);
PAINT GREEN (-6325 4725);
DISPLAY INVISIBLE (-6325 4725);
FORCEPROP 2 LAST PATH I73
J 0
(-6375 4875);
DISPLAY 1.021277 (-6375 4875);
PAINT ORANGE (-6375 4875);
DISPLAY INVISIBLE (-6375 4875);
FORCEADD TAP..6
(-5575 4075);
FORCEPROP 3 LASTPIN (-5525 4075) SIG_NAME M_F_DQ<51>
J 0
(-5515 4085);
DISPLAY 0.659574 (-5515 4085);
PAINT MONO (-5515 4085);
DISPLAY INVISIBLE (-5515 4085);
FORCEPROP 1 LASTPIN (-5525 4075) BN 51
J 0
(-5577 4083);
DISPLAY 0.617021 (-5577 4083);
PAINT PINK (-5577 4083);
FORCEPROP 2 LAST CDS_LIB mstr_standard
J 0
(-5575 4075);
PAINT MONO (-5575 4075);
DISPLAY INVISIBLE (-5575 4075);
FORCEPROP 1 LAST BODY_TYPE PLUMBING
J 0
(-5575 4025);
DISPLAY 1.595745 (-5575 4025);
PAINT GREEN (-5575 4025);
DISPLAY INVISIBLE (-5575 4025);
FORCEPROP 1 LAST HDL_TAP TRUE
J 0
(-5250 3950);
DISPLAY 1.595745 (-5250 3950);
PAINT GREEN (-5250 3950);
DISPLAY INVISIBLE (-5250 3950);
FORCEPROP 1 LAST PATH I74
J 0
(-5577 4075);
DISPLAY 0.872340 (-5577 4075);
PAINT GREEN (-5577 4075);
DISPLAY INVISIBLE (-5577 4075);
FORCEADD TAP..6
(-5575 4125);
FORCEPROP 3 LASTPIN (-5525 4125) SIG_NAME M_F_DQ<52>
J 0
(-5515 4135);
DISPLAY 0.659574 (-5515 4135);
PAINT MONO (-5515 4135);
DISPLAY INVISIBLE (-5515 4135);
FORCEPROP 1 LASTPIN (-5525 4125) BN 52
J 0
(-5577 4133);
DISPLAY 0.617021 (-5577 4133);
PAINT PINK (-5577 4133);
FORCEPROP 2 LAST CDS_LIB mstr_standard
J 0
(-5575 4125);
PAINT MONO (-5575 4125);
DISPLAY INVISIBLE (-5575 4125);
FORCEPROP 1 LAST BODY_TYPE PLUMBING
J 0
(-5575 4075);
DISPLAY 1.595745 (-5575 4075);
PAINT GREEN (-5575 4075);
DISPLAY INVISIBLE (-5575 4075);
FORCEPROP 1 LAST HDL_TAP TRUE
J 0
(-5250 4000);
DISPLAY 1.595745 (-5250 4000);
PAINT GREEN (-5250 4000);
DISPLAY INVISIBLE (-5250 4000);
FORCEPROP 1 LAST PATH I75
J 0
(-5577 4125);
DISPLAY 0.872340 (-5577 4125);
PAINT GREEN (-5577 4125);
DISPLAY INVISIBLE (-5577 4125);
FORCEADD TAP..6
(-5575 4175);
FORCEPROP 3 LASTPIN (-5525 4175) SIG_NAME M_F_DQ<53>
J 0
(-5515 4185);
DISPLAY 0.659574 (-5515 4185);
PAINT MONO (-5515 4185);
DISPLAY INVISIBLE (-5515 4185);
FORCEPROP 1 LASTPIN (-5525 4175) BN 53
J 0
(-5577 4183);
DISPLAY 0.617021 (-5577 4183);
PAINT PINK (-5577 4183);
FORCEPROP 2 LAST CDS_LIB mstr_standard
J 0
(-5575 4175);
PAINT MONO (-5575 4175);
DISPLAY INVISIBLE (-5575 4175);
FORCEPROP 1 LAST BODY_TYPE PLUMBING
J 0
(-5575 4125);
DISPLAY 1.595745 (-5575 4125);
PAINT GREEN (-5575 4125);
DISPLAY INVISIBLE (-5575 4125);
FORCEPROP 1 LAST HDL_TAP TRUE
J 0
(-5250 4050);
DISPLAY 1.595745 (-5250 4050);
PAINT GREEN (-5250 4050);
DISPLAY INVISIBLE (-5250 4050);
FORCEPROP 1 LAST PATH I76
J 0
(-5577 4175);
DISPLAY 0.872340 (-5577 4175);
PAINT GREEN (-5577 4175);
DISPLAY INVISIBLE (-5577 4175);
FORCEADD TAP..6
(-5575 4225);
FORCEPROP 3 LASTPIN (-5525 4225) SIG_NAME M_F_DQ<54>
J 0
(-5515 4235);
DISPLAY 0.659574 (-5515 4235);
PAINT MONO (-5515 4235);
DISPLAY INVISIBLE (-5515 4235);
FORCEPROP 1 LASTPIN (-5525 4225) BN 54
J 0
(-5577 4233);
DISPLAY 0.617021 (-5577 4233);
PAINT PINK (-5577 4233);
FORCEPROP 2 LAST CDS_LIB mstr_standard
J 0
(-5575 4225);
PAINT MONO (-5575 4225);
DISPLAY INVISIBLE (-5575 4225);
FORCEPROP 1 LAST BODY_TYPE PLUMBING
J 0
(-5575 4175);
DISPLAY 1.595745 (-5575 4175);
PAINT GREEN (-5575 4175);
DISPLAY INVISIBLE (-5575 4175);
FORCEPROP 1 LAST HDL_TAP TRUE
J 0
(-5250 4100);
DISPLAY 1.595745 (-5250 4100);
PAINT GREEN (-5250 4100);
DISPLAY INVISIBLE (-5250 4100);
FORCEPROP 1 LAST PATH I77
J 0
(-5577 4225);
DISPLAY 0.872340 (-5577 4225);
PAINT GREEN (-5577 4225);
DISPLAY INVISIBLE (-5577 4225);
FORCEADD TAP..6
(-5575 4275);
FORCEPROP 3 LASTPIN (-5525 4275) SIG_NAME M_F_DQ<55>
J 0
(-5515 4285);
DISPLAY 0.659574 (-5515 4285);
PAINT MONO (-5515 4285);
DISPLAY INVISIBLE (-5515 4285);
FORCEPROP 1 LASTPIN (-5525 4275) BN 55
J 0
(-5577 4283);
DISPLAY 0.617021 (-5577 4283);
PAINT PINK (-5577 4283);
FORCEPROP 2 LAST CDS_LIB mstr_standard
J 0
(-5575 4275);
PAINT MONO (-5575 4275);
DISPLAY INVISIBLE (-5575 4275);
FORCEPROP 1 LAST BODY_TYPE PLUMBING
J 0
(-5575 4225);
DISPLAY 1.595745 (-5575 4225);
PAINT GREEN (-5575 4225);
DISPLAY INVISIBLE (-5575 4225);
FORCEPROP 1 LAST HDL_TAP TRUE
J 0
(-5250 4150);
DISPLAY 1.595745 (-5250 4150);
PAINT GREEN (-5250 4150);
DISPLAY INVISIBLE (-5250 4150);
FORCEPROP 1 LAST PATH I78
J 0
(-5577 4275);
DISPLAY 0.872340 (-5577 4275);
PAINT GREEN (-5577 4275);
DISPLAY INVISIBLE (-5577 4275);
FORCEADD TAP..6
(-5575 4325);
FORCEPROP 3 LASTPIN (-5525 4325) SIG_NAME M_F_DQ<56>
J 0
(-5515 4335);
DISPLAY 0.659574 (-5515 4335);
PAINT MONO (-5515 4335);
DISPLAY INVISIBLE (-5515 4335);
FORCEPROP 1 LASTPIN (-5525 4325) BN 56
J 0
(-5577 4333);
DISPLAY 0.617021 (-5577 4333);
PAINT PINK (-5577 4333);
FORCEPROP 2 LAST CDS_LIB mstr_standard
J 0
(-5575 4325);
PAINT MONO (-5575 4325);
DISPLAY INVISIBLE (-5575 4325);
FORCEPROP 1 LAST BODY_TYPE PLUMBING
J 0
(-5575 4275);
DISPLAY 1.595745 (-5575 4275);
PAINT GREEN (-5575 4275);
DISPLAY INVISIBLE (-5575 4275);
FORCEPROP 1 LAST HDL_TAP TRUE
J 0
(-5250 4200);
DISPLAY 1.595745 (-5250 4200);
PAINT GREEN (-5250 4200);
DISPLAY INVISIBLE (-5250 4200);
FORCEPROP 1 LAST PATH I79
J 0
(-5577 4325);
DISPLAY 0.872340 (-5577 4325);
PAINT GREEN (-5577 4325);
DISPLAY INVISIBLE (-5577 4325);
FORCEADD TAP..6
(-5575 725);
FORCEPROP 3 LASTPIN (-5525 725) SIG_NAME M_F_CLK_DN<2>
J 0
(-5515 735);
DISPLAY 0.659574 (-5515 735);
PAINT MONO (-5515 735);
DISPLAY INVISIBLE (-5515 735);
FORCEPROP 1 LASTPIN (-5525 725) BN 2
J 0
(-5577 733);
DISPLAY 0.617021 (-5577 733);
PAINT PINK (-5577 733);
FORCEPROP 2 LAST CDS_LIB mstr_standard
J 0
(-5575 725);
PAINT MONO (-5575 725);
DISPLAY INVISIBLE (-5575 725);
FORCEPROP 1 LAST BODY_TYPE PLUMBING
J 0
(-5575 675);
DISPLAY 1.595745 (-5575 675);
PAINT GREEN (-5575 675);
DISPLAY INVISIBLE (-5575 675);
FORCEPROP 1 LAST HDL_TAP TRUE
J 0
(-5250 600);
DISPLAY 1.595745 (-5250 600);
PAINT GREEN (-5250 600);
DISPLAY INVISIBLE (-5250 600);
FORCEPROP 1 LAST PATH I8
J 0
(-5577 725);
DISPLAY 0.872340 (-5577 725);
PAINT GREEN (-5577 725);
DISPLAY INVISIBLE (-5577 725);
FORCEADD TAP..6
(-5575 4375);
FORCEPROP 3 LASTPIN (-5525 4375) SIG_NAME M_F_DQ<57>
J 0
(-5515 4385);
DISPLAY 0.659574 (-5515 4385);
PAINT MONO (-5515 4385);
DISPLAY INVISIBLE (-5515 4385);
FORCEPROP 1 LASTPIN (-5525 4375) BN 57
J 0
(-5577 4383);
DISPLAY 0.617021 (-5577 4383);
PAINT PINK (-5577 4383);
FORCEPROP 2 LAST CDS_LIB mstr_standard
J 0
(-5575 4375);
PAINT MONO (-5575 4375);
DISPLAY INVISIBLE (-5575 4375);
FORCEPROP 1 LAST BODY_TYPE PLUMBING
J 0
(-5575 4325);
DISPLAY 1.595745 (-5575 4325);
PAINT GREEN (-5575 4325);
DISPLAY INVISIBLE (-5575 4325);
FORCEPROP 1 LAST HDL_TAP TRUE
J 0
(-5250 4250);
DISPLAY 1.595745 (-5250 4250);
PAINT GREEN (-5250 4250);
DISPLAY INVISIBLE (-5250 4250);
FORCEPROP 1 LAST PATH I80
J 0
(-5577 4375);
DISPLAY 0.872340 (-5577 4375);
PAINT GREEN (-5577 4375);
DISPLAY INVISIBLE (-5577 4375);
FORCEADD TAP..6
(-5575 4425);
FORCEPROP 3 LASTPIN (-5525 4425) SIG_NAME M_F_DQ<58>
J 0
(-5515 4435);
DISPLAY 0.659574 (-5515 4435);
PAINT MONO (-5515 4435);
DISPLAY INVISIBLE (-5515 4435);
FORCEPROP 1 LASTPIN (-5525 4425) BN 58
J 0
(-5577 4433);
DISPLAY 0.617021 (-5577 4433);
PAINT PINK (-5577 4433);
FORCEPROP 2 LAST CDS_LIB mstr_standard
J 0
(-5575 4425);
PAINT MONO (-5575 4425);
DISPLAY INVISIBLE (-5575 4425);
FORCEPROP 1 LAST BODY_TYPE PLUMBING
J 0
(-5575 4375);
DISPLAY 1.595745 (-5575 4375);
PAINT GREEN (-5575 4375);
DISPLAY INVISIBLE (-5575 4375);
FORCEPROP 1 LAST HDL_TAP TRUE
J 0
(-5250 4300);
DISPLAY 1.595745 (-5250 4300);
PAINT GREEN (-5250 4300);
DISPLAY INVISIBLE (-5250 4300);
FORCEPROP 1 LAST PATH I81
J 0
(-5577 4425);
DISPLAY 0.872340 (-5577 4425);
PAINT GREEN (-5577 4425);
DISPLAY INVISIBLE (-5577 4425);
FORCEADD TAP..6
(-5575 4475);
FORCEPROP 3 LASTPIN (-5525 4475) SIG_NAME M_F_DQ<59>
J 0
(-5515 4485);
DISPLAY 0.659574 (-5515 4485);
PAINT MONO (-5515 4485);
DISPLAY INVISIBLE (-5515 4485);
FORCEPROP 1 LASTPIN (-5525 4475) BN 59
J 0
(-5577 4483);
DISPLAY 0.617021 (-5577 4483);
PAINT PINK (-5577 4483);
FORCEPROP 2 LAST CDS_LIB mstr_standard
J 0
(-5575 4475);
PAINT MONO (-5575 4475);
DISPLAY INVISIBLE (-5575 4475);
FORCEPROP 1 LAST BODY_TYPE PLUMBING
J 0
(-5575 4425);
DISPLAY 1.595745 (-5575 4425);
PAINT GREEN (-5575 4425);
DISPLAY INVISIBLE (-5575 4425);
FORCEPROP 1 LAST HDL_TAP TRUE
J 0
(-5250 4350);
DISPLAY 1.595745 (-5250 4350);
PAINT GREEN (-5250 4350);
DISPLAY INVISIBLE (-5250 4350);
FORCEPROP 1 LAST PATH I82
J 0
(-5577 4475);
DISPLAY 0.872340 (-5577 4475);
PAINT GREEN (-5577 4475);
DISPLAY INVISIBLE (-5577 4475);
FORCEADD TAP..6
(-5575 4525);
FORCEPROP 3 LASTPIN (-5525 4525) SIG_NAME M_F_DQ<60>
J 0
(-5515 4535);
DISPLAY 0.659574 (-5515 4535);
PAINT MONO (-5515 4535);
DISPLAY INVISIBLE (-5515 4535);
FORCEPROP 1 LASTPIN (-5525 4525) BN 60
J 0
(-5577 4533);
DISPLAY 0.617021 (-5577 4533);
PAINT PINK (-5577 4533);
FORCEPROP 2 LAST CDS_LIB mstr_standard
J 0
(-5575 4525);
PAINT MONO (-5575 4525);
DISPLAY INVISIBLE (-5575 4525);
FORCEPROP 1 LAST BODY_TYPE PLUMBING
J 0
(-5575 4475);
DISPLAY 1.595745 (-5575 4475);
PAINT GREEN (-5575 4475);
DISPLAY INVISIBLE (-5575 4475);
FORCEPROP 1 LAST HDL_TAP TRUE
J 0
(-5250 4400);
DISPLAY 1.595745 (-5250 4400);
PAINT GREEN (-5250 4400);
DISPLAY INVISIBLE (-5250 4400);
FORCEPROP 1 LAST PATH I83
J 0
(-5577 4525);
DISPLAY 0.872340 (-5577 4525);
PAINT GREEN (-5577 4525);
DISPLAY INVISIBLE (-5577 4525);
FORCEADD TAP..6
(-5575 4575);
FORCEPROP 3 LASTPIN (-5525 4575) SIG_NAME M_F_DQ<61>
J 0
(-5515 4585);
DISPLAY 0.659574 (-5515 4585);
PAINT MONO (-5515 4585);
DISPLAY INVISIBLE (-5515 4585);
FORCEPROP 1 LASTPIN (-5525 4575) BN 61
J 0
(-5577 4583);
DISPLAY 0.617021 (-5577 4583);
PAINT PINK (-5577 4583);
FORCEPROP 2 LAST CDS_LIB mstr_standard
J 0
(-5575 4575);
PAINT MONO (-5575 4575);
DISPLAY INVISIBLE (-5575 4575);
FORCEPROP 1 LAST BODY_TYPE PLUMBING
J 0
(-5575 4525);
DISPLAY 1.595745 (-5575 4525);
PAINT GREEN (-5575 4525);
DISPLAY INVISIBLE (-5575 4525);
FORCEPROP 1 LAST HDL_TAP TRUE
J 0
(-5250 4450);
DISPLAY 1.595745 (-5250 4450);
PAINT GREEN (-5250 4450);
DISPLAY INVISIBLE (-5250 4450);
FORCEPROP 1 LAST PATH I84
J 0
(-5577 4575);
DISPLAY 0.872340 (-5577 4575);
PAINT GREEN (-5577 4575);
DISPLAY INVISIBLE (-5577 4575);
FORCEADD TAP..6
(-5575 4625);
FORCEPROP 3 LASTPIN (-5525 4625) SIG_NAME M_F_DQ<62>
J 0
(-5515 4635);
DISPLAY 0.659574 (-5515 4635);
PAINT MONO (-5515 4635);
DISPLAY INVISIBLE (-5515 4635);
FORCEPROP 1 LASTPIN (-5525 4625) BN 62
J 0
(-5577 4633);
DISPLAY 0.617021 (-5577 4633);
PAINT PINK (-5577 4633);
FORCEPROP 2 LAST CDS_LIB mstr_standard
J 0
(-5575 4625);
PAINT MONO (-5575 4625);
DISPLAY INVISIBLE (-5575 4625);
FORCEPROP 1 LAST BODY_TYPE PLUMBING
J 0
(-5575 4575);
DISPLAY 1.595745 (-5575 4575);
PAINT GREEN (-5575 4575);
DISPLAY INVISIBLE (-5575 4575);
FORCEPROP 1 LAST HDL_TAP TRUE
J 0
(-5250 4500);
DISPLAY 1.595745 (-5250 4500);
PAINT GREEN (-5250 4500);
DISPLAY INVISIBLE (-5250 4500);
FORCEPROP 1 LAST PATH I85
J 0
(-5577 4625);
DISPLAY 0.872340 (-5577 4625);
PAINT GREEN (-5577 4625);
DISPLAY INVISIBLE (-5577 4625);
FORCEADD TAP..6
(-5575 4675);
FORCEPROP 3 LASTPIN (-5525 4675) SIG_NAME M_F_DQ<63>
J 0
(-5515 4685);
DISPLAY 0.659574 (-5515 4685);
PAINT MONO (-5515 4685);
DISPLAY INVISIBLE (-5515 4685);
FORCEPROP 1 LASTPIN (-5525 4675) BN 63
J 0
(-5577 4683);
DISPLAY 0.617021 (-5577 4683);
PAINT PINK (-5577 4683);
FORCEPROP 2 LAST CDS_LIB mstr_standard
J 0
(-5575 4675);
PAINT MONO (-5575 4675);
DISPLAY INVISIBLE (-5575 4675);
FORCEPROP 1 LAST BODY_TYPE PLUMBING
J 0
(-5575 4625);
DISPLAY 1.595745 (-5575 4625);
PAINT GREEN (-5575 4625);
DISPLAY INVISIBLE (-5575 4625);
FORCEPROP 1 LAST HDL_TAP TRUE
J 0
(-5250 4550);
DISPLAY 1.595745 (-5250 4550);
PAINT GREEN (-5250 4550);
DISPLAY INVISIBLE (-5250 4550);
FORCEPROP 1 LAST PATH I86
J 0
(-5577 4675);
DISPLAY 0.872340 (-5577 4675);
PAINT GREEN (-5577 4675);
DISPLAY INVISIBLE (-5577 4675);
FORCEADD TAP..6
R 2
(-2850 825);
FORCEPROP 3 LASTPIN (-2900 825) SIG_NAME M_F_BG<0>
J 0
(-2890 835);
DISPLAY 0.659574 (-2890 835);
PAINT MONO (-2890 835);
DISPLAY INVISIBLE (-2890 835);
FORCEPROP 1 LASTPIN (-2900 825) BN 0
J 2
(-2848 833);
DISPLAY 0.617021 (-2848 833);
PAINT PINK (-2848 833);
FORCEPROP 2 LAST CDS_LIB mstr_standard
J 0
(-2850 825);
PAINT MONO (-2850 825);
DISPLAY INVISIBLE (-2850 825);
FORCEPROP 1 LAST BODY_TYPE PLUMBING
J 2
(-2850 775);
DISPLAY 1.595745 (-2850 775);
PAINT GREEN (-2850 775);
DISPLAY INVISIBLE (-2850 775);
FORCEPROP 1 LAST HDL_TAP TRUE
J 2
(-3175 700);
DISPLAY 1.595745 (-3175 700);
PAINT GREEN (-3175 700);
DISPLAY INVISIBLE (-3175 700);
FORCEPROP 1 LAST PATH I87
J 2
(-2848 825);
DISPLAY 0.872340 (-2848 825);
PAINT GREEN (-2848 825);
DISPLAY INVISIBLE (-2848 825);
FORCEADD TAP..6
R 2
(-2850 775);
FORCEPROP 3 LASTPIN (-2900 775) SIG_NAME M_F_BA<1>
J 0
(-2890 785);
DISPLAY 0.659574 (-2890 785);
PAINT MONO (-2890 785);
DISPLAY INVISIBLE (-2890 785);
FORCEPROP 1 LASTPIN (-2900 775) BN 1
J 2
(-2848 783);
DISPLAY 0.617021 (-2848 783);
PAINT PINK (-2848 783);
FORCEPROP 2 LAST CDS_LIB mstr_standard
J 0
(-2850 775);
PAINT MONO (-2850 775);
DISPLAY INVISIBLE (-2850 775);
FORCEPROP 1 LAST BODY_TYPE PLUMBING
J 2
(-2850 725);
DISPLAY 1.595745 (-2850 725);
PAINT GREEN (-2850 725);
DISPLAY INVISIBLE (-2850 725);
FORCEPROP 1 LAST HDL_TAP TRUE
J 2
(-3175 650);
DISPLAY 1.595745 (-3175 650);
PAINT GREEN (-3175 650);
DISPLAY INVISIBLE (-3175 650);
FORCEPROP 1 LAST PATH I88
J 2
(-2848 775);
DISPLAY 0.872340 (-2848 775);
PAINT GREEN (-2848 775);
DISPLAY INVISIBLE (-2848 775);
FORCEADD TAP..6
R 2
(-2850 725);
FORCEPROP 3 LASTPIN (-2900 725) SIG_NAME M_F_BA<0>
J 0
(-2890 735);
DISPLAY 0.659574 (-2890 735);
PAINT MONO (-2890 735);
DISPLAY INVISIBLE (-2890 735);
FORCEPROP 1 LASTPIN (-2900 725) BN 0
J 2
(-2848 733);
DISPLAY 0.617021 (-2848 733);
PAINT PINK (-2848 733);
FORCEPROP 2 LAST CDS_LIB mstr_standard
J 0
(-2850 725);
PAINT MONO (-2850 725);
DISPLAY INVISIBLE (-2850 725);
FORCEPROP 1 LAST BODY_TYPE PLUMBING
J 2
(-2850 675);
DISPLAY 1.595745 (-2850 675);
PAINT GREEN (-2850 675);
DISPLAY INVISIBLE (-2850 675);
FORCEPROP 1 LAST HDL_TAP TRUE
J 2
(-3175 600);
DISPLAY 1.595745 (-3175 600);
PAINT GREEN (-3175 600);
DISPLAY INVISIBLE (-3175 600);
FORCEPROP 1 LAST PATH I89
J 2
(-2848 725);
DISPLAY 0.872340 (-2848 725);
PAINT GREEN (-2848 725);
DISPLAY INVISIBLE (-2848 725);
FORCEADD TAP..6
(-5575 825);
FORCEPROP 3 LASTPIN (-5525 825) SIG_NAME M_F_CLK_DP<0>
J 0
(-5515 835);
DISPLAY 0.659574 (-5515 835);
PAINT MONO (-5515 835);
DISPLAY INVISIBLE (-5515 835);
FORCEPROP 1 LASTPIN (-5525 825) BN 0
J 0
(-5577 833);
DISPLAY 0.617021 (-5577 833);
PAINT PINK (-5577 833);
FORCEPROP 2 LAST CDS_LIB mstr_standard
J 0
(-5575 825);
PAINT MONO (-5575 825);
DISPLAY INVISIBLE (-5575 825);
FORCEPROP 1 LAST BODY_TYPE PLUMBING
J 0
(-5575 775);
DISPLAY 1.595745 (-5575 775);
PAINT GREEN (-5575 775);
DISPLAY INVISIBLE (-5575 775);
FORCEPROP 1 LAST HDL_TAP TRUE
J 0
(-5250 700);
DISPLAY 1.595745 (-5250 700);
PAINT GREEN (-5250 700);
DISPLAY INVISIBLE (-5250 700);
FORCEPROP 1 LAST PATH I9
J 0
(-5577 825);
DISPLAY 0.872340 (-5577 825);
PAINT GREEN (-5577 825);
DISPLAY INVISIBLE (-5577 825);
FORCEADD TAP..6
R 2
(-2850 875);
FORCEPROP 3 LASTPIN (-2900 875) SIG_NAME M_F_BG<1>
J 0
(-2890 885);
DISPLAY 0.659574 (-2890 885);
PAINT MONO (-2890 885);
DISPLAY INVISIBLE (-2890 885);
FORCEPROP 1 LASTPIN (-2900 875) BN 1
J 2
(-2848 883);
DISPLAY 0.617021 (-2848 883);
PAINT PINK (-2848 883);
FORCEPROP 2 LAST CDS_LIB mstr_standard
J 0
(-2850 875);
PAINT MONO (-2850 875);
DISPLAY INVISIBLE (-2850 875);
FORCEPROP 1 LAST BODY_TYPE PLUMBING
J 2
(-2850 825);
DISPLAY 1.595745 (-2850 825);
PAINT GREEN (-2850 825);
DISPLAY INVISIBLE (-2850 825);
FORCEPROP 1 LAST HDL_TAP TRUE
J 2
(-3175 750);
DISPLAY 1.595745 (-3175 750);
PAINT GREEN (-3175 750);
DISPLAY INVISIBLE (-3175 750);
FORCEPROP 1 LAST PATH I90
J 2
(-2848 875);
DISPLAY 0.872340 (-2848 875);
PAINT GREEN (-2848 875);
DISPLAY INVISIBLE (-2848 875);
FORCEADD TAP..6
R 2
(-2850 1025);
FORCEPROP 3 LASTPIN (-2900 1025) SIG_NAME M_F_CS_N<1>
J 0
(-2890 1035);
DISPLAY 0.659574 (-2890 1035);
PAINT MONO (-2890 1035);
DISPLAY INVISIBLE (-2890 1035);
FORCEPROP 1 LASTPIN (-2900 1025) BN 1
J 2
(-2848 1033);
DISPLAY 0.617021 (-2848 1033);
PAINT PINK (-2848 1033);
FORCEPROP 2 LAST CDS_LIB mstr_standard
J 0
(-2850 1025);
PAINT MONO (-2850 1025);
DISPLAY INVISIBLE (-2850 1025);
FORCEPROP 1 LAST BODY_TYPE PLUMBING
J 2
(-2850 975);
DISPLAY 1.595745 (-2850 975);
PAINT GREEN (-2850 975);
DISPLAY INVISIBLE (-2850 975);
FORCEPROP 1 LAST HDL_TAP TRUE
J 2
(-3175 900);
DISPLAY 1.595745 (-3175 900);
PAINT GREEN (-3175 900);
DISPLAY INVISIBLE (-3175 900);
FORCEPROP 1 LAST PATH I91
J 2
(-2848 1025);
DISPLAY 0.872340 (-2848 1025);
PAINT GREEN (-2848 1025);
DISPLAY INVISIBLE (-2848 1025);
FORCEADD TAP..6
R 2
(-2850 975);
FORCEPROP 3 LASTPIN (-2900 975) SIG_NAME M_F_CS_N<0>
J 0
(-2890 985);
DISPLAY 0.659574 (-2890 985);
PAINT MONO (-2890 985);
DISPLAY INVISIBLE (-2890 985);
FORCEPROP 1 LASTPIN (-2900 975) BN 0
J 2
(-2848 983);
DISPLAY 0.617021 (-2848 983);
PAINT PINK (-2848 983);
FORCEPROP 2 LAST CDS_LIB mstr_standard
J 0
(-2850 975);
PAINT MONO (-2850 975);
DISPLAY INVISIBLE (-2850 975);
FORCEPROP 1 LAST BODY_TYPE PLUMBING
J 2
(-2850 925);
DISPLAY 1.595745 (-2850 925);
PAINT GREEN (-2850 925);
DISPLAY INVISIBLE (-2850 925);
FORCEPROP 1 LAST HDL_TAP TRUE
J 2
(-3175 850);
DISPLAY 1.595745 (-3175 850);
PAINT GREEN (-3175 850);
DISPLAY INVISIBLE (-3175 850);
FORCEPROP 1 LAST PATH I92
J 2
(-2848 975);
DISPLAY 0.872340 (-2848 975);
PAINT GREEN (-2848 975);
DISPLAY INVISIBLE (-2848 975);
FORCEADD TAP..6
R 2
(-2850 1075);
FORCEPROP 3 LASTPIN (-2900 1075) SIG_NAME M_F_CS_N<2>
J 0
(-2890 1085);
DISPLAY 0.659574 (-2890 1085);
PAINT MONO (-2890 1085);
DISPLAY INVISIBLE (-2890 1085);
FORCEPROP 1 LASTPIN (-2900 1075) BN 2
J 2
(-2848 1083);
DISPLAY 0.617021 (-2848 1083);
PAINT PINK (-2848 1083);
FORCEPROP 2 LAST CDS_LIB mstr_standard
J 0
(-2850 1075);
PAINT MONO (-2850 1075);
DISPLAY INVISIBLE (-2850 1075);
FORCEPROP 1 LAST BODY_TYPE PLUMBING
J 2
(-2850 1025);
DISPLAY 1.595745 (-2850 1025);
PAINT GREEN (-2850 1025);
DISPLAY INVISIBLE (-2850 1025);
FORCEPROP 1 LAST HDL_TAP TRUE
J 2
(-3175 950);
DISPLAY 1.595745 (-3175 950);
PAINT GREEN (-3175 950);
DISPLAY INVISIBLE (-3175 950);
FORCEPROP 1 LAST PATH I93
J 2
(-2848 1075);
DISPLAY 0.872340 (-2848 1075);
PAINT GREEN (-2848 1075);
DISPLAY INVISIBLE (-2848 1075);
FORCEADD TAP..6
R 2
(-2850 1225);
FORCEPROP 3 LASTPIN (-2900 1225) SIG_NAME M_F_CS_N<5>
J 0
(-2890 1235);
DISPLAY 0.659574 (-2890 1235);
PAINT MONO (-2890 1235);
DISPLAY INVISIBLE (-2890 1235);
FORCEPROP 1 LASTPIN (-2900 1225) BN 5
J 2
(-2848 1233);
DISPLAY 0.617021 (-2848 1233);
PAINT PINK (-2848 1233);
FORCEPROP 2 LAST CDS_LIB mstr_standard
J 0
(-2850 1225);
PAINT MONO (-2850 1225);
DISPLAY INVISIBLE (-2850 1225);
FORCEPROP 1 LAST BODY_TYPE PLUMBING
J 2
(-2850 1175);
DISPLAY 1.595745 (-2850 1175);
PAINT GREEN (-2850 1175);
DISPLAY INVISIBLE (-2850 1175);
FORCEPROP 1 LAST HDL_TAP TRUE
J 2
(-3175 1100);
DISPLAY 1.595745 (-3175 1100);
PAINT GREEN (-3175 1100);
DISPLAY INVISIBLE (-3175 1100);
FORCEPROP 1 LAST PATH I94
J 2
(-2848 1225);
DISPLAY 0.872340 (-2848 1225);
PAINT GREEN (-2848 1225);
DISPLAY INVISIBLE (-2848 1225);
FORCEADD TAP..6
R 2
(-2850 1125);
FORCEPROP 3 LASTPIN (-2900 1125) SIG_NAME M_F_CS_N<3>
J 0
(-2890 1135);
DISPLAY 0.659574 (-2890 1135);
PAINT MONO (-2890 1135);
DISPLAY INVISIBLE (-2890 1135);
FORCEPROP 1 LASTPIN (-2900 1125) BN 3
J 2
(-2848 1133);
DISPLAY 0.617021 (-2848 1133);
PAINT PINK (-2848 1133);
FORCEPROP 2 LAST CDS_LIB mstr_standard
J 0
(-2850 1125);
PAINT MONO (-2850 1125);
DISPLAY INVISIBLE (-2850 1125);
FORCEPROP 1 LAST BODY_TYPE PLUMBING
J 2
(-2850 1075);
DISPLAY 1.595745 (-2850 1075);
PAINT GREEN (-2850 1075);
DISPLAY INVISIBLE (-2850 1075);
FORCEPROP 1 LAST HDL_TAP TRUE
J 2
(-3175 1000);
DISPLAY 1.595745 (-3175 1000);
PAINT GREEN (-3175 1000);
DISPLAY INVISIBLE (-3175 1000);
FORCEPROP 1 LAST PATH I95
J 2
(-2848 1125);
DISPLAY 0.872340 (-2848 1125);
PAINT GREEN (-2848 1125);
DISPLAY INVISIBLE (-2848 1125);
FORCEADD TAP..6
R 2
(-2850 1175);
FORCEPROP 3 LASTPIN (-2900 1175) SIG_NAME M_F_CS_N<4>
J 0
(-2890 1185);
DISPLAY 0.659574 (-2890 1185);
PAINT MONO (-2890 1185);
DISPLAY INVISIBLE (-2890 1185);
FORCEPROP 1 LASTPIN (-2900 1175) BN 4
J 2
(-2848 1183);
DISPLAY 0.617021 (-2848 1183);
PAINT PINK (-2848 1183);
FORCEPROP 2 LAST CDS_LIB mstr_standard
J 0
(-2850 1175);
PAINT MONO (-2850 1175);
DISPLAY INVISIBLE (-2850 1175);
FORCEPROP 1 LAST BODY_TYPE PLUMBING
J 2
(-2850 1125);
DISPLAY 1.595745 (-2850 1125);
PAINT GREEN (-2850 1125);
DISPLAY INVISIBLE (-2850 1125);
FORCEPROP 1 LAST HDL_TAP TRUE
J 2
(-3175 1050);
DISPLAY 1.595745 (-3175 1050);
PAINT GREEN (-3175 1050);
DISPLAY INVISIBLE (-3175 1050);
FORCEPROP 1 LAST PATH I96
J 2
(-2848 1175);
DISPLAY 0.872340 (-2848 1175);
PAINT GREEN (-2848 1175);
DISPLAY INVISIBLE (-2848 1175);
FORCEADD TAP..6
R 2
(-2850 1275);
FORCEPROP 3 LASTPIN (-2900 1275) SIG_NAME M_F_CS_N<6>
J 0
(-2890 1285);
DISPLAY 0.659574 (-2890 1285);
PAINT MONO (-2890 1285);
DISPLAY INVISIBLE (-2890 1285);
FORCEPROP 1 LASTPIN (-2900 1275) BN 6
J 2
(-2848 1283);
DISPLAY 0.617021 (-2848 1283);
PAINT PINK (-2848 1283);
FORCEPROP 2 LAST CDS_LIB mstr_standard
J 0
(-2850 1275);
PAINT MONO (-2850 1275);
DISPLAY INVISIBLE (-2850 1275);
FORCEPROP 1 LAST BODY_TYPE PLUMBING
J 2
(-2850 1225);
DISPLAY 1.595745 (-2850 1225);
PAINT GREEN (-2850 1225);
DISPLAY INVISIBLE (-2850 1225);
FORCEPROP 1 LAST HDL_TAP TRUE
J 2
(-3175 1150);
DISPLAY 1.595745 (-3175 1150);
PAINT GREEN (-3175 1150);
DISPLAY INVISIBLE (-3175 1150);
FORCEPROP 1 LAST PATH I97
J 2
(-2848 1275);
DISPLAY 0.872340 (-2848 1275);
PAINT GREEN (-2848 1275);
DISPLAY INVISIBLE (-2848 1275);
FORCEADD TAP..6
R 2
(-2850 1325);
FORCEPROP 3 LASTPIN (-2900 1325) SIG_NAME M_F_CS_N<7>
J 0
(-2890 1335);
DISPLAY 0.659574 (-2890 1335);
PAINT MONO (-2890 1335);
DISPLAY INVISIBLE (-2890 1335);
FORCEPROP 1 LASTPIN (-2900 1325) BN 7
J 2
(-2848 1333);
DISPLAY 0.617021 (-2848 1333);
PAINT PINK (-2848 1333);
FORCEPROP 2 LAST CDS_LIB mstr_standard
J 0
(-2850 1325);
PAINT MONO (-2850 1325);
DISPLAY INVISIBLE (-2850 1325);
FORCEPROP 1 LAST BODY_TYPE PLUMBING
J 2
(-2850 1275);
DISPLAY 1.595745 (-2850 1275);
PAINT GREEN (-2850 1275);
DISPLAY INVISIBLE (-2850 1275);
FORCEPROP 1 LAST HDL_TAP TRUE
J 2
(-3175 1200);
DISPLAY 1.595745 (-3175 1200);
PAINT GREEN (-3175 1200);
DISPLAY INVISIBLE (-3175 1200);
FORCEPROP 1 LAST PATH I98
J 2
(-2848 1325);
DISPLAY 0.872340 (-2848 1325);
PAINT GREEN (-2848 1325);
DISPLAY INVISIBLE (-2848 1325);
FORCEADD TAP..6
R 2
(-2850 1475);
FORCEPROP 3 LASTPIN (-2900 1475) SIG_NAME M_F_ODT<1>
J 0
(-2890 1485);
DISPLAY 0.659574 (-2890 1485);
PAINT MONO (-2890 1485);
DISPLAY INVISIBLE (-2890 1485);
FORCEPROP 1 LASTPIN (-2900 1475) BN 1
J 2
(-2848 1483);
DISPLAY 0.617021 (-2848 1483);
PAINT PINK (-2848 1483);
FORCEPROP 2 LAST CDS_LIB mstr_standard
J 0
(-2850 1475);
PAINT MONO (-2850 1475);
DISPLAY INVISIBLE (-2850 1475);
FORCEPROP 1 LAST BODY_TYPE PLUMBING
J 2
(-2850 1425);
DISPLAY 1.595745 (-2850 1425);
PAINT GREEN (-2850 1425);
DISPLAY INVISIBLE (-2850 1425);
FORCEPROP 1 LAST HDL_TAP TRUE
J 2
(-3175 1350);
DISPLAY 1.595745 (-3175 1350);
PAINT GREEN (-3175 1350);
DISPLAY INVISIBLE (-3175 1350);
FORCEPROP 1 LAST PATH I99
J 2
(-2848 1475);
DISPLAY 0.872340 (-2848 1475);
PAINT GREEN (-2848 1475);
DISPLAY INVISIBLE (-2848 1475);
FORCEADD DESIGN_NOTE..1
(-6500 400);
FORCEPROP 0 LAST L1 CPU SYMBOLS 1-30 ARE PRELIMINARY AND SUBJECT TO CHANGE
J 0
(-6700 275);
DISPLAY 1.021277 (-6700 275);
PAINT ORANGE (-6700 275);
FORCEPROP 2 LAST CDS_LIB mstr_symbols
J 0
(-6500 400);
PAINT ORANGE (-6500 400);
DISPLAY INVISIBLE (-6500 400);
FORCEPROP 1 LAST COMMENT_BODY TRUE
J 0
(-6475 500);
DISPLAY 0.978723 (-6475 500);
PAINT ORANGE (-6475 500);
DISPLAY INVISIBLE (-6475 500);
FORCEADD PRELIM..10
(-4215 2565);
PAINT GRAY (-4215 2565);
FORCEPROP 2 LAST CDS_LIB mstr_misc
J 0
(-4215 2565);
PAINT ORANGE (-4215 2565);
DISPLAY INVISIBLE (-4215 2565);
FORCEPROP 1 LAST COMMENT_BODY TRUE
J 0
(-4215 2565);
PAINT ORANGE (-4215 2565);
DISPLAY INVISIBLE (-4215 2565);
FORCEADD INTEL_CORP_BPAGE..1
(0 0);
FORCEPROP 1 LAST CDS_CON_LAST_MODIFIED Tue Dec 01 11:51:19 2015
J 0
(-1425 325);
DISPLAY 1.340426 (-1425 325);
PAINT GREEN (-1425 325);
DISPLAY INVISIBLE (-1425 325);
FORCEPROP 1 LAST CUSTOM_TXT_CDS <CURRENT_DESIGN_SHEET> OF <TOTAL_DESIGN_SHEETS>
J 0
(-500 25);
PAINT GREEN (-500 25);
FORCEPROP 1 LAST CUSTOM_TXT_CDS <CON_LAST_MODIFIED>
J 0
(-1925 350);
PAINT GREEN (-1925 350);
FORCEPROP 2 LAST CUSTOM_TXT_CDS <XR_PAGE_TITLE>
J 0
(-7890 5250);
DISPLAY 0.638298 (-7890 5250);
PAINT PINK (-7890 5250);
DISPLAY INVISIBLE (-7890 5250);
FORCEPROP 1 LAST SCH_ADDRESS3 Santa Clara, CA 95052-8119
J 0
(-3975 25);
DISPLAY 0.617021 (-3975 25);
PAINT GREEN (-3975 25);
FORCEPROP 1 LAST SCH_ADDRESS2 P.O. BOX 58119
J 0
(-3975 75);
DISPLAY 0.617021 (-3975 75);
PAINT GREEN (-3975 75);
FORCEPROP 1 LAST SCH_ADDRESS1 2200 Mission College Blvd.
J 0
(-3975 125);
DISPLAY 0.617021 (-3975 125);
PAINT GREEN (-3975 125);
FORCEPROP 1 LAST SCH_TITLE SKYLAKE - SKT0 - 8 OF 21
J 0
(-7950 50);
DISPLAY 1.212766 (-7950 50);
PAINT GREEN (-7950 50);
FORCEPROP 1 LAST SCH_NUMBER H4694802
J 0
(-1300 150);
DISPLAY 1.212766 (-1300 150);
PAINT YELLOW (-1300 150);
FORCEPROP 1 LAST SCH_DEPT BESD
J 1
(-4450 100);
DISPLAY 1.212766 (-4450 100);
PAINT YELLOW (-4450 100);
FORCEPROP 1 LAST SCH_REV 2.420
J 0
(-250 150);
DISPLAY 0.978723 (-250 150);
PAINT YELLOW (-250 150);
FORCEPROP 2 LAST CDS_LIB mstr_symbols
J 0
(0 0);
PAINT ORANGE (0 0);
DISPLAY INVISIBLE (0 0);
FORCEPROP 2 LAST PAGE_BORDER TRUE
J 0
(-7890 5250);
DISPLAY 0.851064 (-7890 5250);
PAINT PINK (-7890 5250);
DISPLAY INVISIBLE (-7890 5250);
FORCEPROP 1 LAST COMMENT_BODY TRUE
J 0
(12 12);
DISPLAY 0.638298 (12 12);
PAINT GREEN (12 12);
DISPLAY INVISIBLE (12 12);
FORCEPROP 2 LAST CDS_XR_PAGE_TITLE CR-28 : @BASEBOARD_FAB2_LIB.BASEBOARD_FAB2(SCH_1):PAGE28
J 0
(-7890 5250);
DISPLAY 0.638298 (-7890 5250);
PAINT PINK (-7890 5250);
DISPLAY INVISIBLE (-7890 5250);
WIRE 17 -1 (-2800 4650)(-2800 4700);
WIRE 17 -1 (-2800 4600)(-2800 4650);
WIRE 17 -1 (-2800 4700)(-2800 4750);
WIRE 17 -1 (-2050 4750)(-2800 4750);
FORCEPROP 2 LAST SIG_NAME M_F_DQS_DP<17:0>
J 0
(-2700 4760);
DISPLAY 0.617021 (-2700 4760);
PAINT ORANGE (-2700 4760);
WIRE 17 -1 (-2800 4550)(-2800 4600);
WIRE 17 -1 (-2800 4500)(-2800 4550);
WIRE 17 -1 (-2800 4450)(-2800 4500);
WIRE 17 -1 (-2800 4400)(-2800 4450);
WIRE 17 -1 (-2800 4350)(-2800 4400);
WIRE 17 -1 (-2800 4300)(-2800 4350);
WIRE 17 -1 (-2800 4250)(-2800 4300);
WIRE 17 -1 (-2800 4200)(-2800 4250);
WIRE 17 -1 (-2800 4150)(-2800 4200);
WIRE 17 -1 (-2800 4100)(-2800 4150);
WIRE 17 -1 (-2800 4050)(-2800 4100);
WIRE 17 -1 (-2800 4000)(-2800 4050);
WIRE 17 -1 (-2800 3950)(-2800 4000);
WIRE 17 -1 (-2800 3900)(-2800 3950);
WIRE 17 -1 (-2800 3850)(-2800 3900);
WIRE 17 -1 (-2800 3700)(-2800 3750);
WIRE 17 -1 (-2800 3650)(-2800 3700);
WIRE 17 -1 (-2800 3750)(-2800 3775);
WIRE 17 -1 (-2050 3775)(-2800 3775);
FORCEPROP 2 LAST SIG_NAME M_F_DQS_DN<17:0>
J 0
(-2700 3785);
DISPLAY 0.617021 (-2700 3785);
PAINT ORANGE (-2700 3785);
WIRE 17 -1 (-2800 3600)(-2800 3650);
WIRE 17 -1 (-2800 3550)(-2800 3600);
WIRE 17 -1 (-2800 3500)(-2800 3550);
WIRE 17 -1 (-2800 3450)(-2800 3500);
WIRE 17 -1 (-2800 3400)(-2800 3450);
WIRE 17 -1 (-2800 3350)(-2800 3400);
WIRE 17 -1 (-2800 3300)(-2800 3350);
WIRE 17 -1 (-2800 3250)(-2800 3300);
WIRE 17 -1 (-2800 3200)(-2800 3250);
WIRE 17 -1 (-2800 3150)(-2800 3200);
WIRE 17 -1 (-2800 3100)(-2800 3150);
WIRE 17 -1 (-2800 3050)(-2800 3100);
WIRE 17 -1 (-2800 3000)(-2800 3050);
WIRE 17 -1 (-2800 2950)(-2800 3000);
WIRE 17 -1 (-2800 2900)(-2800 2950);
WIRE 17 -1 (-2800 2750)(-2800 2800);
WIRE 17 -1 (-2800 2700)(-2800 2750);
WIRE 17 -1 (-2800 2800)(-2800 2825);
WIRE 17 -1 (-2050 2825)(-2800 2825);
FORCEPROP 2 LAST SIG_NAME M_F_MA<17:0>
J 0
(-2700 2835);
DISPLAY 0.617021 (-2700 2835);
PAINT ORANGE (-2700 2835);
WIRE 17 -1 (-2800 2650)(-2800 2700);
WIRE 17 -1 (-2800 2600)(-2800 2650);
WIRE 17 -1 (-2800 2550)(-2800 2600);
WIRE 17 -1 (-2800 2500)(-2800 2550);
WIRE 17 -1 (-2800 2450)(-2800 2500);
WIRE 17 -1 (-2800 2400)(-2800 2450);
WIRE 17 -1 (-2800 2350)(-2800 2400);
WIRE 17 -1 (-2800 2300)(-2800 2350);
WIRE 17 -1 (-2800 2250)(-2800 2300);
WIRE 17 -1 (-2800 2200)(-2800 2250);
WIRE 17 -1 (-2800 2150)(-2800 2200);
WIRE 17 -1 (-2800 2100)(-2800 2150);
WIRE 17 -1 (-2800 2050)(-2800 2100);
WIRE 17 -1 (-2800 2000)(-2800 2050);
WIRE 17 -1 (-2800 1950)(-2800 2000);
WIRE 17 -1 (-2800 800)(-2800 825);
WIRE 17 -1 (-2800 750)(-2800 800);
WIRE 17 -1 (-2050 825)(-2800 825);
FORCEPROP 2 LAST SIG_NAME M_F_BA<1:0>
J 0
(-2700 835);
DISPLAY 0.617021 (-2700 835);
PAINT ORANGE (-2700 835);
WIRE 17 -1 (-2800 850)(-2800 900);
WIRE 17 -1 (-2800 900)(-2800 925);
WIRE 17 -1 (-2050 925)(-2800 925);
FORCEPROP 2 LAST SIG_NAME M_F_BG<1:0>
J 0
(-2700 935);
DISPLAY 0.617021 (-2700 935);
PAINT ORANGE (-2700 935);
WIRE 17 -1 (-2800 1800)(-2800 1850);
WIRE 17 -1 (-2800 1750)(-2800 1800);
WIRE 17 -1 (-2800 1850)(-2800 1875);
WIRE 17 -1 (-2050 1875)(-2800 1875);
FORCEPROP 2 LAST SIG_NAME M_F_CKE<3:0>
J 0
(-2700 1885);
DISPLAY 0.617021 (-2700 1885);
PAINT ORANGE (-2700 1885);
WIRE 17 -1 (-2800 1700)(-2800 1750);
WIRE 17 -1 (-2800 1300)(-2800 1350);
WIRE 17 -1 (-2800 1250)(-2800 1300);
WIRE 17 -1 (-2800 1350)(-2800 1375);
WIRE 17 -1 (-2050 1375)(-2800 1375);
FORCEPROP 2 LAST SIG_NAME M_F_CS_N<7:0>
J 0
(-2700 1385);
DISPLAY 0.617021 (-2700 1385);
PAINT ORANGE (-2700 1385);
WIRE 17 -1 (-2800 1200)(-2800 1250);
WIRE 17 -1 (-2800 1150)(-2800 1200);
WIRE 17 -1 (-2800 1100)(-2800 1150);
WIRE 17 -1 (-2800 1050)(-2800 1100);
WIRE 17 -1 (-2800 1000)(-2800 1050);
WIRE 17 -1 (-2800 1550)(-2800 1600);
WIRE 17 -1 (-2800 1500)(-2800 1550);
WIRE 17 -1 (-2800 1600)(-2800 1625);
WIRE 17 -1 (-2050 1625)(-2800 1625);
FORCEPROP 2 LAST SIG_NAME M_F_ODT<3:0>
J 0
(-2700 1635);
DISPLAY 0.617021 (-2700 1635);
PAINT ORANGE (-2700 1635);
WIRE 17 -1 (-2800 1450)(-2800 1500);
WIRE 17 -1 (-5625 4650)(-5625 4700);
WIRE 17 -1 (-5625 4600)(-5625 4650);
WIRE 17 -1 (-5625 4700)(-5625 4800);
WIRE 17 -1 (-5625 4800)(-6375 4800);
FORCEPROP 2 LAST SIG_NAME M_F_DQ<63:0>
J 0
(-6325 4810);
DISPLAY 0.617021 (-6325 4810);
PAINT ORANGE (-6325 4810);
WIRE 17 -1 (-5625 4550)(-5625 4600);
WIRE 17 -1 (-5625 4500)(-5625 4550);
WIRE 17 -1 (-5625 4450)(-5625 4500);
WIRE 17 -1 (-5625 4400)(-5625 4450);
WIRE 17 -1 (-5625 4350)(-5625 4400);
WIRE 17 -1 (-5625 4300)(-5625 4350);
WIRE 17 -1 (-5625 4250)(-5625 4300);
WIRE 17 -1 (-5625 4200)(-5625 4250);
WIRE 17 -1 (-5625 4150)(-5625 4200);
WIRE 17 -1 (-5625 4100)(-5625 4150);
WIRE 17 -1 (-5625 4050)(-5625 4100);
WIRE 17 -1 (-5625 4000)(-5625 4050);
WIRE 17 -1 (-5625 3950)(-5625 4000);
WIRE 17 -1 (-5625 3900)(-5625 3950);
WIRE 17 -1 (-5625 3850)(-5625 3900);
WIRE 17 -1 (-5625 3800)(-5625 3850);
WIRE 17 -1 (-5625 3750)(-5625 3800);
WIRE 17 -1 (-5625 3700)(-5625 3750);
WIRE 17 -1 (-5625 3650)(-5625 3700);
WIRE 17 -1 (-5625 3600)(-5625 3650);
WIRE 17 -1 (-5625 3550)(-5625 3600);
WIRE 17 -1 (-5625 3500)(-5625 3550);
WIRE 17 -1 (-5625 3450)(-5625 3500);
WIRE 17 -1 (-5625 3400)(-5625 3450);
WIRE 17 -1 (-5625 3350)(-5625 3400);
WIRE 17 -1 (-5625 3300)(-5625 3350);
WIRE 17 -1 (-5625 3250)(-5625 3300);
WIRE 17 -1 (-5625 3200)(-5625 3250);
WIRE 17 -1 (-5625 3150)(-5625 3200);
WIRE 17 -1 (-5625 3100)(-5625 3150);
WIRE 17 -1 (-5625 3050)(-5625 3100);
WIRE 17 -1 (-5625 3000)(-5625 3050);
WIRE 17 -1 (-5625 2950)(-5625 3000);
WIRE 17 -1 (-5625 2900)(-5625 2950);
WIRE 17 -1 (-5625 2850)(-5625 2900);
WIRE 17 -1 (-5625 2800)(-5625 2850);
WIRE 17 -1 (-5625 2750)(-5625 2800);
WIRE 17 -1 (-5625 2700)(-5625 2750);
WIRE 17 -1 (-5625 2650)(-5625 2700);
WIRE 17 -1 (-5625 2600)(-5625 2650);
WIRE 17 -1 (-5625 2550)(-5625 2600);
WIRE 17 -1 (-5625 2500)(-5625 2550);
WIRE 17 -1 (-5625 2450)(-5625 2500);
WIRE 17 -1 (-5625 2400)(-5625 2450);
WIRE 17 -1 (-5625 2350)(-5625 2400);
WIRE 17 -1 (-5625 2300)(-5625 2350);
WIRE 17 -1 (-5625 2250)(-5625 2300);
WIRE 17 -1 (-5625 2200)(-5625 2250);
WIRE 17 -1 (-5625 2150)(-5625 2200);
WIRE 17 -1 (-5625 2100)(-5625 2150);
WIRE 17 -1 (-5625 2050)(-5625 2100);
WIRE 17 -1 (-5625 2000)(-5625 2050);
WIRE 17 -1 (-5625 1950)(-5625 2000);
WIRE 17 -1 (-5625 1900)(-5625 1950);
WIRE 17 -1 (-5625 1850)(-5625 1900);
WIRE 17 -1 (-5625 1800)(-5625 1850);
WIRE 17 -1 (-5625 1750)(-5625 1800);
WIRE 17 -1 (-5625 1700)(-5625 1750);
WIRE 17 -1 (-5625 1650)(-5625 1700);
WIRE 17 -1 (-5625 1600)(-5625 1650);
WIRE 17 -1 (-5625 1550)(-5625 1600);
WIRE 17 -1 (-5625 750)(-5625 800);
WIRE 17 -1 (-5625 700)(-5625 750);
WIRE 17 -1 (-5625 800)(-5625 825);
WIRE 17 -1 (-5625 825)(-6375 825);
FORCEPROP 2 LAST SIG_NAME M_F_CLK_DN<3:0>
J 0
(-6325 835);
DISPLAY 0.617021 (-6325 835);
PAINT ORANGE (-6325 835);
WIRE 17 -1 (-5625 650)(-5625 700);
WIRE 17 -1 (-5625 950)(-5625 1000);
WIRE 17 -1 (-5625 900)(-5625 950);
WIRE 17 -1 (-5625 1000)(-5625 1025);
WIRE 17 -1 (-5625 1025)(-6375 1025);
FORCEPROP 2 LAST SIG_NAME M_F_CLK_DP<3:0>
J 0
(-6325 1035);
DISPLAY 0.617021 (-6325 1035);
PAINT ORANGE (-6325 1035);
WIRE 17 -1 (-5625 850)(-5625 900);
WIRE 17 -1 (-5625 1400)(-5625 1450);
WIRE 17 -1 (-5625 1350)(-5625 1400);
WIRE 17 -1 (-5625 1450)(-5625 1475);
WIRE 17 -1 (-5625 1475)(-6375 1475);
FORCEPROP 2 LAST SIG_NAME M_F_ECC<7:0>
J 0
(-6325 1485);
DISPLAY 0.617021 (-6325 1485);
PAINT ORANGE (-6325 1485);
WIRE 17 -1 (-5625 1300)(-5625 1350);
WIRE 17 -1 (-5625 1250)(-5625 1300);
WIRE 17 -1 (-5625 1200)(-5625 1250);
WIRE 17 -1 (-5625 1150)(-5625 1200);
WIRE 17 -1 (-5625 1100)(-5625 1150);
WIRE 16 -1 (-5525 1775)(-5025 1775);
WIRE 16 -1 (-5025 525)(-6375 525);
FORCEPROP 2 LAST SIG_NAME M_F_C<2>
J 0
(-6325 535);
DISPLAY 0.617021 (-6325 535);
PAINT ORANGE (-6325 535);
WIRE 16 -1 (-5025 1075)(-5525 1075);
WIRE 16 -1 (-5025 1125)(-5525 1125);
WIRE 16 -1 (-5025 1175)(-5525 1175);
WIRE 16 -1 (-5025 1225)(-5525 1225);
WIRE 16 -1 (-5025 1275)(-5525 1275);
WIRE 16 -1 (-5025 1325)(-5525 1325);
WIRE 16 -1 (-5025 1375)(-5525 1375);
WIRE 16 -1 (-5025 1425)(-5525 1425);
WIRE 16 -1 (-5525 1525)(-5025 1525);
WIRE 16 -1 (-5525 1575)(-5025 1575);
WIRE 16 -1 (-5525 1625)(-5025 1625);
WIRE 16 -1 (-5025 1675)(-5525 1675);
WIRE 16 -1 (-5525 1725)(-5025 1725);
WIRE 16 -1 (-5025 1825)(-5525 1825);
WIRE 16 -1 (-5525 1875)(-5025 1875);
WIRE 16 -1 (-5525 1925)(-5025 1925);
WIRE 16 -1 (-5525 1975)(-5025 1975);
WIRE 16 -1 (-5525 2025)(-5025 2025);
WIRE 16 -1 (-5025 825)(-5525 825);
WIRE 16 -1 (-5025 875)(-5525 875);
WIRE 16 -1 (-5025 925)(-5525 925);
WIRE 16 -1 (-5025 975)(-5525 975);
WIRE 16 -1 (-5025 625)(-5525 625);
WIRE 16 -1 (-5025 675)(-5525 675);
WIRE 16 -1 (-5025 725)(-5525 725);
WIRE 16 -1 (-5025 775)(-5525 775);
WIRE 16 -1 (-5525 2075)(-5025 2075);
WIRE 16 -1 (-5525 2125)(-5025 2125);
WIRE 16 -1 (-5525 2175)(-5025 2175);
WIRE 16 -1 (-5525 2225)(-5025 2225);
WIRE 16 -1 (-5525 2275)(-5025 2275);
WIRE 16 -1 (-5525 2325)(-5025 2325);
WIRE 16 -1 (-5525 2375)(-5025 2375);
WIRE 16 -1 (-5525 2425)(-5025 2425);
WIRE 16 -1 (-5525 2475)(-5025 2475);
WIRE 16 -1 (-5525 2525)(-5025 2525);
WIRE 16 -1 (-5525 2575)(-5025 2575);
WIRE 16 -1 (-5525 2625)(-5025 2625);
WIRE 16 -1 (-5525 2675)(-5025 2675);
WIRE 16 -1 (-5525 2725)(-5025 2725);
WIRE 16 -1 (-5525 2775)(-5025 2775);
WIRE 16 -1 (-5525 2825)(-5025 2825);
WIRE 16 -1 (-5525 2875)(-5025 2875);
WIRE 16 -1 (-5525 2925)(-5025 2925);
WIRE 16 -1 (-5525 2975)(-5025 2975);
WIRE 16 -1 (-5525 3025)(-5025 3025);
WIRE 16 -1 (-5525 3075)(-5025 3075);
WIRE 16 -1 (-5525 3125)(-5025 3125);
WIRE 16 -1 (-5525 3175)(-5025 3175);
WIRE 16 -1 (-5525 3225)(-5025 3225);
WIRE 16 -1 (-5525 3275)(-5025 3275);
WIRE 16 -1 (-5525 3325)(-5025 3325);
WIRE 16 -1 (-5025 3375)(-5525 3375);
WIRE 16 -1 (-5525 3425)(-5025 3425);
WIRE 16 -1 (-5525 3475)(-5025 3475);
WIRE 16 -1 (-5025 3525)(-5525 3525);
WIRE 16 -1 (-5525 3575)(-5025 3575);
WIRE 16 -1 (-5525 3625)(-5025 3625);
WIRE 16 -1 (-5025 3675)(-5525 3675);
WIRE 16 -1 (-5025 3725)(-5525 3725);
WIRE 16 -1 (-5025 3775)(-5525 3775);
WIRE 16 -1 (-5025 3825)(-5525 3825);
WIRE 16 -1 (-5025 3875)(-5525 3875);
WIRE 16 -1 (-5025 3925)(-5525 3925);
WIRE 16 -1 (-5025 3975)(-5525 3975);
WIRE 16 -1 (-5025 4025)(-5525 4025);
WIRE 16 -1 (-5025 4075)(-5525 4075);
WIRE 16 -1 (-5025 4125)(-5525 4125);
WIRE 16 -1 (-5025 4175)(-5525 4175);
WIRE 16 -1 (-5025 4225)(-5525 4225);
WIRE 16 -1 (-5025 4275)(-5525 4275);
WIRE 16 -1 (-5025 4325)(-5525 4325);
WIRE 16 -1 (-5025 4375)(-5525 4375);
WIRE 16 -1 (-5025 4425)(-5525 4425);
WIRE 16 -1 (-5025 4475)(-5525 4475);
WIRE 16 -1 (-5025 4525)(-5525 4525);
WIRE 16 -1 (-5025 4575)(-5525 4575);
WIRE 16 -1 (-5025 4625)(-5525 4625);
WIRE 16 -1 (-5025 4675)(-5525 4675);
WIRE 16 -1 (-3325 1425)(-2900 1425);
WIRE 16 -1 (-3325 1475)(-2900 1475);
WIRE 16 -1 (-3325 1525)(-2900 1525);
WIRE 16 -1 (-3325 1575)(-2900 1575);
WIRE 16 -1 (-3325 1925)(-2900 1925);
WIRE 16 -1 (-3325 1975)(-2900 1975);
WIRE 16 -1 (-3325 2025)(-2900 2025);
WIRE 16 -1 (-3325 975)(-2900 975);
WIRE 16 -1 (-3325 1025)(-2900 1025);
WIRE 16 -1 (-3325 1075)(-2900 1075);
WIRE 16 -1 (-3325 1125)(-2900 1125);
WIRE 16 -1 (-3325 1175)(-2900 1175);
WIRE 16 -1 (-3325 1225)(-2900 1225);
WIRE 16 -1 (-3325 1275)(-2900 1275);
WIRE 16 -1 (-3325 1325)(-2900 1325);
WIRE 16 -1 (-3325 1675)(-2900 1675);
WIRE 16 -1 (-3325 1725)(-2900 1725);
WIRE 16 -1 (-3325 1775)(-2900 1775);
WIRE 16 -1 (-3325 1825)(-2900 1825);
WIRE 16 -1 (-3325 825)(-2900 825);
WIRE 16 -1 (-3325 875)(-2900 875);
WIRE 16 -1 (-3325 725)(-2900 725);
WIRE 16 -1 (-3325 775)(-2900 775);
WIRE 16 -1 (-3325 575)(-2050 575);
FORCEPROP 2 LAST SIG_NAME M_F_ALERT_N
J 0
(-2725 585);
DISPLAY 0.617021 (-2725 585);
PAINT ORANGE (-2725 585);
WIRE 16 -1 (-3325 525)(-2050 525);
FORCEPROP 2 LAST SIG_NAME M_F_PAR
J 0
(-2725 535);
DISPLAY 0.617021 (-2725 535);
PAINT ORANGE (-2725 535);
WIRE 16 -1 (-3325 625)(-2050 625);
FORCEPROP 2 LAST SIG_NAME M_F_ACT_N
J 0
(-2725 635);
DISPLAY 0.617021 (-2725 635);
PAINT ORANGE (-2725 635);
WIRE 16 -1 (-3325 2075)(-2900 2075);
WIRE 16 -1 (-2900 2125)(-3325 2125);
WIRE 16 -1 (-3325 2175)(-2900 2175);
WIRE 16 -1 (-3325 2225)(-2900 2225);
WIRE 16 -1 (-2900 2275)(-3325 2275);
WIRE 16 -1 (-3325 2325)(-2900 2325);
WIRE 16 -1 (-2900 2375)(-3325 2375);
WIRE 16 -1 (-2900 2425)(-3325 2425);
WIRE 16 -1 (-3325 2475)(-2900 2475);
WIRE 16 -1 (-2900 2525)(-3325 2525);
WIRE 16 -1 (-2900 2575)(-3325 2575);
WIRE 16 -1 (-2900 2625)(-3325 2625);
WIRE 16 -1 (-2900 2675)(-3325 2675);
WIRE 16 -1 (-3325 2725)(-2900 2725);
WIRE 16 -1 (-2900 2775)(-3325 2775);
WIRE 16 -1 (-3325 3825)(-2900 3825);
WIRE 16 -1 (-3325 3875)(-2900 3875);
WIRE 16 -1 (-3325 3925)(-2900 3925);
WIRE 16 -1 (-3325 3975)(-2900 3975);
WIRE 16 -1 (-3325 4025)(-2900 4025);
WIRE 16 -1 (-3325 4075)(-2900 4075);
WIRE 16 -1 (-3325 2875)(-2900 2875);
WIRE 16 -1 (-2900 2925)(-3325 2925);
WIRE 16 -1 (-2900 2975)(-3325 2975);
WIRE 16 -1 (-2900 3025)(-3325 3025);
WIRE 16 -1 (-2900 3075)(-3325 3075);
WIRE 16 -1 (-3325 3125)(-2900 3125);
WIRE 16 -1 (-2900 3175)(-3325 3175);
WIRE 16 -1 (-2900 3225)(-3325 3225);
WIRE 16 -1 (-2900 3275)(-3325 3275);
WIRE 16 -1 (-2900 3325)(-3325 3325);
WIRE 16 -1 (-3325 3375)(-2900 3375);
WIRE 16 -1 (-3325 3425)(-2900 3425);
WIRE 16 -1 (-3325 3475)(-2900 3475);
WIRE 16 -1 (-3325 3525)(-2900 3525);
WIRE 16 -1 (-3325 3575)(-2900 3575);
WIRE 16 -1 (-3325 3625)(-2900 3625);
WIRE 16 -1 (-3325 3675)(-2900 3675);
WIRE 16 -1 (-3325 3725)(-2900 3725);
WIRE 16 -1 (-3325 4125)(-2900 4125);
WIRE 16 -1 (-3325 4175)(-2900 4175);
WIRE 16 -1 (-3325 4225)(-2900 4225);
WIRE 16 -1 (-3325 4275)(-2900 4275);
WIRE 16 -1 (-3325 4325)(-2900 4325);
WIRE 16 -1 (-3325 4375)(-2900 4375);
WIRE 16 -1 (-3325 4425)(-2900 4425);
WIRE 16 -1 (-3325 4475)(-2900 4475);
WIRE 16 -1 (-3325 4525)(-2900 4525);
WIRE 16 -1 (-3325 4575)(-2900 4575);
WIRE 16 -1 (-3325 4625)(-2900 4625);
WIRE 16 -1 (-3325 4675)(-2900 4675);
FORCENOTE
ROOM=CPU0
(-7925 350) 0;
DISPLAY LEFT (-7925 350);
DISPLAY 1.382979 (-7925 350);
PAINT PURPLE (-7925 350);
FORCENOTE
BOM_COST=PROC_SOCKET
(-7925 225) 0;
DISPLAY LEFT (-7925 225);
DISPLAY 1.382979 (-7925 225);
PAINT PURPLE (-7925 225);
QUIT
